(kicad_pcb
	(version 20241229)
	(generator "pcbnew")
	(generator_version "9.0")
	(general
		(thickness 1.6)
		(legacy_teardrops no)
	)
	(paper "A4")
	(title_block
		(title "LPDDR4 testbed")
		(date "2024-03-26")
		(rev "1.2.2")
	)
	(layers
		(0 "F.Cu" signal)
		(4 "In1.Cu" power)
		(6 "In2.Cu" power)
		(8 "In3.Cu" signal)
		(10 "In4.Cu" signal)
		(2 "B.Cu" signal)
		(9 "F.Adhes" user "F.Adhesive")
		(11 "B.Adhes" user "B.Adhesive")
		(13 "F.Paste" user)
		(15 "B.Paste" user)
		(5 "F.SilkS" user "F.Silkscreen")
		(7 "B.SilkS" user "B.Silkscreen")
		(1 "F.Mask" user)
		(3 "B.Mask" user)
		(17 "Dwgs.User" user "User.Drawings")
		(19 "Cmts.User" user "User.Comments")
		(21 "Eco1.User" user "User.Eco1")
		(23 "Eco2.User" user "User.Eco2")
		(25 "Edge.Cuts" user)
		(27 "Margin" user)
		(31 "F.CrtYd" user "F.Courtyard")
		(29 "B.CrtYd" user "B.Courtyard")
		(35 "F.Fab" user)
		(33 "B.Fab" user)
	)
	(setup
		(stackup
			(layer "F.SilkS"
				(type "Top Silk Screen")
			)
			(layer "F.Paste"
				(type "Top Solder Paste")
			)
			(layer "F.Mask"
				(type "Top Solder Mask")
				(thickness 0.01)
			)
			(layer "F.Cu"
				(type "copper")
				(thickness 0.035)
			)
			(layer "dielectric 1"
				(type "core")
				(thickness 0.274)
				(material "FR4")
				(epsilon_r 4.5)
				(loss_tangent 0.02)
			)
			(layer "In1.Cu"
				(type "copper")
				(thickness 0.035)
			)
			(layer "dielectric 2"
				(type "prepreg")
				(thickness 0.274)
				(material "FR4")
				(epsilon_r 4.5)
				(loss_tangent 0.02)
			)
			(layer "In2.Cu"
				(type "copper")
				(thickness 0.035)
			)
			(layer "dielectric 3"
				(type "core")
				(thickness 0.274)
				(material "FR4")
				(epsilon_r 4.5)
				(loss_tangent 0.02)
			)
			(layer "In3.Cu"
				(type "copper")
				(thickness 0.035)
			)
			(layer "dielectric 4"
				(type "prepreg")
				(thickness 0.274)
				(material "FR4")
				(epsilon_r 4.5)
				(loss_tangent 0.02)
			)
			(layer "In4.Cu"
				(type "copper")
				(thickness 0.035)
			)
			(layer "dielectric 5"
				(type "core")
				(thickness 0.274)
				(material "FR4")
				(epsilon_r 4.5)
				(loss_tangent 0.02)
			)
			(layer "B.Cu"
				(type "copper")
				(thickness 0.035)
			)
			(layer "B.Mask"
				(type "Bottom Solder Mask")
				(thickness 0.01)
			)
			(layer "B.Paste"
				(type "Bottom Solder Paste")
			)
			(layer "B.SilkS"
				(type "Bottom Silk Screen")
			)
			(copper_finish "None")
			(dielectric_constraints no)
		)
		(pad_to_mask_clearance 0.05)
		(allow_soldermask_bridges_in_footprints no)
		(tenting front back)
		(grid_origin 144.975 92.95)
		(pcbplotparams
			(layerselection 0x00000000_00000000_55555555_5755f5ff)
			(plot_on_all_layers_selection 0x00000000_00000000_00000000_00000000)
			(disableapertmacros no)
			(usegerberextensions no)
			(usegerberattributes yes)
			(usegerberadvancedattributes yes)
			(creategerberjobfile yes)
			(dashed_line_dash_ratio 12.000000)
			(dashed_line_gap_ratio 3.000000)
			(svgprecision 6)
			(plotframeref no)
			(mode 1)
			(useauxorigin no)
			(hpglpennumber 1)
			(hpglpenspeed 20)
			(hpglpendiameter 15.000000)
			(pdf_front_fp_property_popups yes)
			(pdf_back_fp_property_popups yes)
			(pdf_metadata yes)
			(pdf_single_document no)
			(dxfpolygonmode yes)
			(dxfimperialunits yes)
			(dxfusepcbnewfont yes)
			(psnegative no)
			(psa4output no)
			(plot_black_and_white yes)
			(sketchpadsonfab no)
			(plotpadnumbers no)
			(hidednponfab no)
			(sketchdnponfab yes)
			(crossoutdnponfab yes)
			(subtractmaskfromsilk no)
			(outputformat 1)
			(mirror no)
			(drillshape 0)
			(scaleselection 1)
			(outputdirectory "./fab")
		)
	)
	(net 0 "")
	(net 1 "Net-(IC1-P0)")
	(net 2 "Net-(IC1-P1)")
	(net 3 "Net-(IC1-P2)")
	(net 4 "unconnected-(J1-Pad51)")
	(net 5 "unconnected-(J1-Pad52)")
	(net 6 "unconnected-(J1-Pad53)")
	(net 7 "unconnected-(J1-Pad54)")
	(net 8 "unconnected-(J1-Pad55)")
	(net 9 "unconnected-(J1-Pad56)")
	(net 10 "unconnected-(J1-Pad57)")
	(net 11 "unconnected-(J1-Pad58)")
	(net 12 "unconnected-(J1-Pad59)")
	(net 13 "unconnected-(J1-Pad60)")
	(net 14 "unconnected-(J1-Pad61)")
	(net 15 "unconnected-(J1-Pad62)")
	(net 16 "unconnected-(J1-Pad63)")
	(net 17 "unconnected-(J1-Pad64)")
	(net 18 "unconnected-(J1-Pad65)")
	(net 19 "unconnected-(J1-Pad66)")
	(net 20 "unconnected-(J1-Pad67)")
	(net 21 "unconnected-(J1-Pad68)")
	(net 22 "unconnected-(J1-Pad69)")
	(net 23 "unconnected-(J1-Pad70)")
	(net 24 "unconnected-(J1-Pad71)")
	(net 25 "unconnected-(J1-Pad72)")
	(net 26 "unconnected-(J1-Pad73)")
	(net 27 "unconnected-(J1-Pad74)")
	(net 28 "unconnected-(J1-Pad75)")
	(net 29 "unconnected-(J1-Pad76)")
	(net 30 "unconnected-(J1-Pad77)")
	(net 31 "unconnected-(J1-Pad78)")
	(net 32 "unconnected-(J1-Pad79)")
	(net 33 "unconnected-(J1-Pad80)")
	(net 34 "unconnected-(J1-Pad81)")
	(net 35 "unconnected-(J1-Pad82)")
	(net 36 "GND")
	(net 37 "unconnected-(J1-Pad83)")
	(net 38 "unconnected-(J1-Pad84)")
	(net 39 "unconnected-(J1-Pad85)")
	(net 40 "unconnected-(J1-Pad86)")
	(net 41 "unconnected-(J1-Pad87)")
	(net 42 "unconnected-(J1-Pad88)")
	(net 43 "unconnected-(J1-Pad89)")
	(net 44 "unconnected-(J1-Pad90)")
	(net 45 "unconnected-(J1-Pad91)")
	(net 46 "unconnected-(J1-Pad92)")
	(net 47 "unconnected-(J1-Pad94)")
	(net 48 "unconnected-(J1-Pad96)")
	(net 49 "unconnected-(J1-Pad98)")
	(net 50 "unconnected-(J1-Pad100)")
	(net 51 "unconnected-(J1-Pad102)")
	(net 52 "unconnected-(J1-Pad104)")
	(net 53 "unconnected-(J1-Pad106)")
	(net 54 "unconnected-(J1-Pad108)")
	(net 55 "unconnected-(J1-Pad109)")
	(net 56 "unconnected-(J1-Pad110)")
	(net 57 "unconnected-(J1-Pad111)")
	(net 58 "unconnected-(J1-Pad112)")
	(net 59 "unconnected-(J1-Pad113)")
	(net 60 "unconnected-(J1-Pad114)")
	(net 61 "unconnected-(J1-Pad115)")
	(net 62 "unconnected-(J1-Pad117)")
	(net 63 "unconnected-(J1-Pad119)")
	(net 64 "unconnected-(J1-Pad121)")
	(net 65 "unconnected-(J1-Pad123)")
	(net 66 "unconnected-(J1-Pad125)")
	(net 67 "unconnected-(J1-Pad131)")
	(net 68 "unconnected-(J1-Pad132)")
	(net 69 "unconnected-(J1-Pad133)")
	(net 70 "unconnected-(J1-Pad134)")
	(net 71 "unconnected-(J1-Pad135)")
	(net 72 "unconnected-(J1-Pad136)")
	(net 73 "unconnected-(J1-Pad137)")
	(net 74 "unconnected-(J1-Pad138)")
	(net 75 "unconnected-(J1-Pad139)")
	(net 76 "unconnected-(J1-Pad140)")
	(net 77 "unconnected-(J1-Pad141)")
	(net 78 "unconnected-(J1-Pad142)")
	(net 79 "unconnected-(J1-Pad143)")
	(net 80 "unconnected-(J1-Pad144)")
	(net 81 "unconnected-(J1-Pad145)")
	(net 82 "unconnected-(J1-Pad146)")
	(net 83 "unconnected-(J1-Pad147)")
	(net 84 "unconnected-(J1-Pad148)")
	(net 85 "unconnected-(J1-Pad149)")
	(net 86 "unconnected-(J1-Pad150)")
	(net 87 "unconnected-(J1-Pad151)")
	(net 88 "unconnected-(J1-Pad152)")
	(net 89 "unconnected-(J1-Pad153)")
	(net 90 "unconnected-(J1-Pad155)")
	(net 91 "unconnected-(J1-Pad157)")
	(net 92 "unconnected-(J1-Pad159)")
	(net 93 "unconnected-(J1-Pad170)")
	(net 94 "unconnected-(J1-Pad172)")
	(net 95 "unconnected-(J1-Pad174)")
	(net 96 "unconnected-(J1-Pad176)")
	(net 97 "unconnected-(J1-Pad178)")
	(net 98 "unconnected-(J1-Pad180)")
	(net 99 "unconnected-(J1-Pad182)")
	(net 100 "unconnected-(J1-Pad188)")
	(net 101 "unconnected-(J1-Pad190)")
	(net 102 "unconnected-(J1-Pad198)")
	(net 103 "unconnected-(J1-Pad202)")
	(net 104 "unconnected-(J1-Pad208)")
	(net 105 "unconnected-(J1-Pad212)")
	(net 106 "unconnected-(J1-Pad213)")
	(net 107 "unconnected-(J1-Pad214)")
	(net 108 "unconnected-(J1-Pad215)")
	(net 109 "unconnected-(J1-Pad216)")
	(net 110 "unconnected-(J1-Pad217)")
	(net 111 "unconnected-(J1-Pad218)")
	(net 112 "unconnected-(J1-Pad219)")
	(net 113 "unconnected-(J1-Pad220)")
	(net 114 "unconnected-(J1-Pad221)")
	(net 115 "unconnected-(J1-Pad222)")
	(net 116 "unconnected-(J1-Pad223)")
	(net 117 "unconnected-(J1-Pad224)")
	(net 118 "unconnected-(J1-Pad225)")
	(net 119 "unconnected-(J1-Pad226)")
	(net 120 "unconnected-(J1-Pad227)")
	(net 121 "unconnected-(J1-Pad228)")
	(net 122 "unconnected-(J1-Pad229)")
	(net 123 "unconnected-(J1-Pad230)")
	(net 124 "unconnected-(J1-Pad231)")
	(net 125 "unconnected-(J1-Pad232)")
	(net 126 "unconnected-(J1-Pad233)")
	(net 127 "unconnected-(J1-Pad234)")
	(net 128 "unconnected-(J1-Pad235)")
	(net 129 "unconnected-(J1-Pad236)")
	(net 130 "unconnected-(J1-Pad237)")
	(net 131 "unconnected-(J1-Pad238)")
	(net 132 "unconnected-(J1-Pad239)")
	(net 133 "unconnected-(J1-Pad240)")
	(net 134 "unconnected-(J1-Pad241)")
	(net 135 "unconnected-(J1-Pad242)")
	(net 136 "unconnected-(J1-Pad243)")
	(net 137 "unconnected-(J1-Pad244)")
	(net 138 "unconnected-(J1-Pad245)")
	(net 139 "unconnected-(J1-Pad247)")
	(net 140 "unconnected-(J1-Pad249)")
	(net 141 "unconnected-(J1-Pad251)")
	(net 142 "unconnected-(J1-Pad252)")
	(net 143 "unconnected-(J1-Pad253)")
	(net 144 "unconnected-(J1-Pad254)")
	(net 145 "unconnected-(J1-Pad255)")
	(net 146 "unconnected-(J1-Pad256)")
	(net 147 "unconnected-(J1-Pad257)")
	(net 148 "unconnected-(J1-Pad258)")
	(net 149 "unconnected-(J1-Pad259)")
	(net 150 "unconnected-(J1-Pad260)")
	(net 151 "Net-(IC1-P3)")
	(net 152 "Net-(IC1-P4)")
	(net 153 "Net-(IC1-P5)")
	(net 154 "unconnected-(IC1-P6-Pad11)")
	(net 155 "unconnected-(IC1-P7-Pad12)")
	(net 156 "unconnected-(IC1-~{INT}-Pad13)")
	(net 157 "Net-(U2-SW)")
	(net 158 "Net-(U1A-ODT_CA_A)")
	(net 159 "Net-(U1B-ODT_CA_B)")
	(net 160 "Net-(U1A-RESET_N)")
	(net 161 "Net-(U1A-ZQ0)")
	(net 162 "unconnected-(U1A-DNU-PadA1)")
	(net 163 "unconnected-(U1A-DNU-PadA2)")
	(net 164 "unconnected-(U1B-NC-PadA8)")
	(net 165 "unconnected-(U1A-DNU-PadA11)")
	(net 166 "unconnected-(U1A-DNU-PadA12)")
	(net 167 "unconnected-(U1B-DNU-PadAA1)")
	(net 168 "unconnected-(U1B-DQ0_B-PadAA2)")
	(net 169 "unconnected-(U1B-DQ7_B-PadAA4)")
	(net 170 "unconnected-(U1B-DQ15_B-PadAA9)")
	(net 171 "unconnected-(U1B-DQ8_B-PadAA11)")
	(net 172 "unconnected-(U1B-DNU-PadAA12)")
	(net 173 "unconnected-(U1B-DNU-PadAB1)")
	(net 174 "unconnected-(U1B-DNU-PadAB2)")
	(net 175 "unconnected-(U1B-DNU-PadAB11)")
	(net 176 "unconnected-(U1B-DNU-PadAB12)")
	(net 177 "unconnected-(U1A-DNU-PadB1)")
	(net 178 "unconnected-(U1A-DNU-PadB12)")
	(net 179 "unconnected-(U1B-NC-PadG11)")
	(net 180 "unconnected-(U1A-NC-PadH3)")
	(net 181 "unconnected-(U1A-NC-PadJ5)")
	(net 182 "unconnected-(U1A-NC-PadK5)")
	(net 183 "unconnected-(U1A-NC-PadK8)")
	(net 184 "unconnected-(U1B-NC-PadN5)")
	(net 185 "unconnected-(U1B-NC-PadN8)")
	(net 186 "unconnected-(U1B-CA1_B-PadP2)")
	(net 187 "VDD1")
	(net 188 "VDD2")
	(net 189 "VDDQ")
	(net 190 "DQ00_A")
	(net 191 "DQ01_A")
	(net 192 "CA0_A")
	(net 193 "DQ02_A")
	(net 194 "CA1_A")
	(net 195 "DQ03_A")
	(net 196 "DQ_S0_TA")
	(net 197 "DQ_S0_CA")
	(net 198 "DQ07_A")
	(net 199 "CKE0_A")
	(net 200 "CS0_A")
	(net 201 "DMI_0A")
	(net 202 "DQ06_A")
	(net 203 "DQ05_A")
	(net 204 "DQ04_A")
	(net 205 "DQ12_A")
	(net 206 "DQ13_A")
	(net 207 "DQ14_A")
	(net 208 "DQ15_A")
	(net 209 "DQ_S1_TA")
	(net 210 "DQ_S1_CA")
	(net 211 "DMI_1A")
	(net 212 "DQ08_A")
	(net 213 "DQ09_A")
	(net 214 "CK_C_A")
	(net 215 "DQ10_A")
	(net 216 "CK_T_A")
	(net 217 "DQ11_A")
	(net 218 "CA2_A")
	(net 219 "CA3_A")
	(net 220 "CA4_A")
	(net 221 "CA5_A")
	(net 222 "CS0_B")
	(net 223 "unconnected-(U1B-CKE0_B-PadP4)")
	(net 224 "unconnected-(U1B-NC-PadP5)")
	(net 225 "unconnected-(U1B-CK_T_B-PadP8)")
	(net 226 "unconnected-(U1B-CK_C_B-PadP9)")
	(net 227 "unconnected-(U1B-CA5_B-PadP11)")
	(net 228 "unconnected-(U1B-CA0_B-PadR2)")
	(net 229 "ODT_CA_A")
	(net 230 "RESET_N")
	(net 231 "unconnected-(U1B-NC-PadR3)")
	(net 232 "unconnected-(U1B-CA2_B-PadR9)")
	(net 233 "unconnected-(U1B-CA3_B-PadR10)")
	(net 234 "unconnected-(U1B-CA4_B-PadR11)")
	(net 235 "unconnected-(U1B-DQ3_B-PadU2)")
	(net 236 "unconnected-(U1B-DQ4_B-PadU4)")
	(net 237 "unconnected-(U1B-DQ12_B-PadU9)")
	(net 238 "unconnected-(U1B-DQ11_B-PadU11)")
	(net 239 "unconnected-(U1B-DQ2_B-PadV2)")
	(net 240 "unconnected-(U1B-DQS0_C_B-PadV3)")
	(net 241 "VDDLED")
	(net 242 "unconnected-(U1B-DQ5_B-PadV4)")
	(net 243 "unconnected-(U1B-DQ13_B-PadV9)")
	(net 244 "unconnected-(U1B-DQS1_C_B-PadV10)")
	(net 245 "unconnected-(U1B-DQ10_B-PadV11)")
	(net 246 "SDA")
	(net 247 "SCL")
	(net 248 "unconnected-(U1B-DQS0_T_B-PadW3)")
	(net 249 "unconnected-(U1B-DQS1_T_B-PadW10)")
	(net 250 "unconnected-(U1B-DQ1_B-PadY2)")
	(net 251 "unconnected-(U1B-DMI0_B-PadY3)")
	(net 252 "unconnected-(U1B-DQ6_B-PadY4)")
	(net 253 "unconnected-(U1B-DQ14_B-PadY9)")
	(net 254 "unconnected-(U1B-DMI1_B-PadY10)")
	(net 255 "Net-(D1-Pad1)")
	(net 256 "Net-(D2-Pad1)")
	(net 257 "Net-(D3-Pad1)")
	(net 258 "Net-(D4-Pad1)")
	(net 259 "unconnected-(U1B-DQ9_B-PadY11)")
	(net 260 "unconnected-(U2-NC-Pad3)")
	(net 261 "unconnected-(U2-NC-Pad5)")
	(footprint "antmicro-footprints:Edge_Conn_Bus_DDR4"
		(locked yes)
		(layer "F.Cu")
		(at 100 100)
		(descr "SODIMM DDR4 Edge Connector")
		(tags "SODIMM DDR4 Edge Connector")
		(property "Reference" "J1"
			(at 0 -4.2 0)
			(layer "F.SilkS")
			(hide yes)
			(effects
				(font
					(size 0.7 0.7)
					(thickness 0.15)
				)
				(justify left bottom)
			)
		)
		(property "Value" "Bus_DDR4_Edge_Conn"
			(at 0 1 0)
			(layer "F.Fab")
			(effects
				(font
					(size 0.7 0.7)
					(thickness 0.15)
				)
				(justify left bottom)
			)
		)
		(property "Description" "DDR SO-DIMM PCB Edge"
			(at 0 0 0)
			(layer "F.Fab")
			(hide yes)
			(effects
				(font
					(size 1.27 1.27)
					(thickness 0.15)
				)
			)
		)
		(property "Author" "Antmicro"
			(at 0 0 0)
			(layer "F.Fab")
			(hide yes)
			(effects
				(font
					(size 1 1)
					(thickness 0.15)
				)
			)
		)
		(property "License" "Apache-2.0"
			(at 0 0 0)
			(layer "F.Fab")
			(hide yes)
			(effects
				(font
					(size 1 1)
					(thickness 0.15)
				)
			)
		)
		(property "MPN" ""
			(at 0 0 0)
			(layer "F.Fab")
			(hide yes)
			(effects
				(font
					(size 1 1)
					(thickness 0.15)
				)
			)
		)
		(property "Manufacturer" ""
			(at 0 0 0)
			(layer "F.Fab")
			(hide yes)
			(effects
				(font
					(size 1 1)
					(thickness 0.15)
				)
			)
		)
		(sheetname "SODIMM")
		(sheetfile "sodim.kicad_sch")
		(attr exclude_from_pos_files exclude_from_bom)
		(fp_circle
			(center 0.6 -3.9)
			(end 0.65 -3.9)
			(stroke
				(width 0.15)
				(type solid)
			)
			(fill yes)
			(layer "F.SilkS")
		)
		(fp_line
			(start 0 -0.75)
			(end 0 -4)
			(stroke
				(width 0.15)
				(type solid)
			)
			(layer "Edge.Cuts")
		)
		(fp_line
			(start 0.75 0)
			(end 37.8 0)
			(stroke
				(width 0.15)
				(type solid)
			)
			(layer "Edge.Cuts")
		)
		(fp_line
			(start 37.8 0)
			(end 37.8 -3.5)
			(stroke
				(width 0.15)
				(type solid)
			)
			(layer "Edge.Cuts")
		)
		(fp_line
			(start 38.8 0)
			(end 38.8 -3.5)
			(stroke
				(width 0.15)
				(type solid)
			)
			(layer "Edge.Cuts")
		)
		(fp_line
			(start 38.8 0)
			(end 68.85 0)
			(stroke
				(width 0.15)
				(type solid)
			)
			(layer "Edge.Cuts")
		)
		(fp_line
			(start 69.6 -0.75)
			(end 69.6 -4)
			(stroke
				(width 0.15)
				(type solid)
			)
			(layer "Edge.Cuts")
		)
		(fp_arc
			(start 0.75 0)
			(mid 0.21967 -0.21967)
			(end 0 -0.75)
			(stroke
				(width 0.15)
				(type solid)
			)
			(layer "Edge.Cuts")
		)
		(fp_arc
			(start 37.8 -3.5)
			(mid 38.3 -4)
			(end 38.8 -3.5)
			(stroke
				(width 0.15)
				(type solid)
			)
			(layer "Edge.Cuts")
		)
		(fp_arc
			(start 69.6 -0.75)
			(mid 69.38033 -0.21967)
			(end 68.85 0)
			(stroke
				(width 0.15)
				(type solid)
			)
			(layer "Edge.Cuts")
		)
		(fp_rect
			(start 0 -4.1)
			(end 69.6 0)
			(stroke
				(width 0.05)
				(type solid)
			)
			(fill no)
			(layer "F.CrtYd")
		)
		(pad "" np_thru_hole circle
			(at 1.999 -6)
			(size 1.8 1.8)
			(drill 1.8)
			(layers "*.Cu" "*.Mask")
		)
		(pad "" np_thru_hole circle
			(at 67.599 -6)
			(size 1.8 1.8)
			(drill 1.8)
			(layers "*.Cu" "*.Mask")
		)
		(pad "1" smd rect
			(at 1.425 -1.301)
			(size 0.35 2.5)
			(layers "F.Cu" "F.Mask")
			(net 36 "GND")
			(pinfunction "1")
			(pintype "passive")
		)
		(pad "2" smd rect
			(at 1.675 -1.301)
			(size 0.35 2.5)
			(layers "B.Cu" "B.Mask")
			(net 36 "GND")
			(pinfunction "2")
			(pintype "passive")
		)
		(pad "3" smd rect
			(at 1.925 -1.301)
			(size 0.35 2.5)
			(layers "F.Cu" "F.Mask")
			(net 36 "GND")
			(pinfunction "3")
			(pintype "passive")
		)
		(pad "4" smd rect
			(at 2.173 -1.301)
			(size 0.35 2.5)
			(layers "B.Cu" "B.Mask")
			(net 36 "GND")
			(pinfunction "4")
			(pintype "passive")
		)
		(pad "5" smd rect
			(at 2.423 -1.301)
			(size 0.35 2.5)
			(layers "F.Cu" "F.Mask")
			(net 36 "GND")
			(pinfunction "5")
			(pintype "passive")
		)
		(pad "6" smd rect
			(at 2.673 -1.301)
			(size 0.35 2.5)
			(layers "B.Cu" "B.Mask")
			(net 36 "GND")
			(pinfunction "6")
			(pintype "passive")
		)
		(pad "7" smd rect
			(at 2.923 -1.301)
			(size 0.35 2.5)
			(layers "F.Cu" "F.Mask")
			(net 36 "GND")
			(pinfunction "7")
			(pintype "passive")
		)
		(pad "8" smd rect
			(at 3.173 -1.301)
			(size 0.35 2.5)
			(layers "B.Cu" "B.Mask")
			(net 36 "GND")
			(pinfunction "8")
			(pintype "passive")
		)
		(pad "9" smd rect
			(at 3.423 -1.301)
			(size 0.35 2.5)
			(layers "F.Cu" "F.Mask")
			(net 36 "GND")
			(pinfunction "9")
			(pintype "passive")
		)
		(pad "10" smd rect
			(at 3.673 -1.301)
			(size 0.35 2.5)
			(layers "B.Cu" "B.Mask")
			(net 36 "GND")
			(pinfunction "10")
			(pintype "passive")
		)
		(pad "11" smd rect
			(at 3.923 -1.301)
			(size 0.35 2.5)
			(layers "F.Cu" "F.Mask")
			(net 36 "GND")
			(pinfunction "11")
			(pintype "passive")
		)
		(pad "12" smd rect
			(at 4.174 -1.301)
			(size 0.35 2.5)
			(layers "B.Cu" "B.Mask")
			(net 36 "GND")
			(pinfunction "12")
			(pintype "passive")
		)
		(pad "13" smd rect
			(at 4.424 -1.301)
			(size 0.35 2.5)
			(layers "F.Cu" "F.Mask")
			(net 36 "GND")
			(pinfunction "13")
			(pintype "passive")
		)
		(pad "14" smd rect
			(at 4.674 -1.301)
			(size 0.35 2.5)
			(layers "B.Cu" "B.Mask")
			(net 36 "GND")
			(pinfunction "14")
			(pintype "passive")
		)
		(pad "15" smd rect
			(at 4.924 -1.301)
			(size 0.35 2.5)
			(layers "F.Cu" "F.Mask")
			(net 36 "GND")
			(pinfunction "15")
			(pintype "passive")
		)
		(pad "16" smd rect
			(at 5.174 -1.301)
			(size 0.35 2.5)
			(layers "B.Cu" "B.Mask")
			(net 36 "GND")
			(pinfunction "16")
			(pintype "passive")
		)
		(pad "17" smd rect
			(at 5.424 -1.301)
			(size 0.35 2.5)
			(layers "F.Cu" "F.Mask")
			(net 36 "GND")
			(pinfunction "17")
			(pintype "passive")
		)
		(pad "18" smd rect
			(at 5.674 -1.301)
			(size 0.35 2.5)
			(layers "B.Cu" "B.Mask")
			(net 36 "GND")
			(pinfunction "18")
			(pintype "passive")
		)
		(pad "19" smd rect
			(at 5.924 -1.301)
			(size 0.35 2.5)
			(layers "F.Cu" "F.Mask")
			(net 36 "GND")
			(pinfunction "19")
			(pintype "passive")
		)
		(pad "20" smd rect
			(at 6.174 -1.301)
			(size 0.35 2.5)
			(layers "B.Cu" "B.Mask")
			(net 36 "GND")
			(pinfunction "20")
			(pintype "passive")
		)
		(pad "21" smd rect
			(at 6.424 -1.301)
			(size 0.35 2.5)
			(layers "F.Cu" "F.Mask")
			(net 36 "GND")
			(pinfunction "21")
			(pintype "passive")
		)
		(pad "22" smd rect
			(at 6.674 -1.301)
			(size 0.35 2.5)
			(layers "B.Cu" "B.Mask")
			(net 36 "GND")
			(pinfunction "22")
			(pintype "passive")
		)
		(pad "23" smd rect
			(at 6.924 -1.301)
			(size 0.35 2.5)
			(layers "F.Cu" "F.Mask")
			(net 36 "GND")
			(pinfunction "23")
			(pintype "passive")
		)
		(pad "24" smd rect
			(at 7.174 -1.301)
			(size 0.35 2.5)
			(layers "B.Cu" "B.Mask")
			(net 36 "GND")
			(pinfunction "24")
			(pintype "passive")
		)
		(pad "25" smd rect
			(at 7.424 -1.301)
			(size 0.35 2.5)
			(layers "F.Cu" "F.Mask")
			(net 36 "GND")
			(pinfunction "25")
			(pintype "passive")
		)
		(pad "26" smd rect
			(at 7.674 -1.301)
			(size 0.35 2.5)
			(layers "B.Cu" "B.Mask")
			(net 36 "GND")
			(pinfunction "26")
			(pintype "passive")
		)
		(pad "27" smd rect
			(at 7.924 -1.301)
			(size 0.35 2.5)
			(layers "F.Cu" "F.Mask")
			(net 36 "GND")
			(pinfunction "27")
			(pintype "passive")
		)
		(pad "28" smd rect
			(at 8.175 -1.301)
			(size 0.35 2.5)
			(layers "B.Cu" "B.Mask")
			(net 36 "GND")
			(pinfunction "28")
			(pintype "passive")
		)
		(pad "29" smd rect
			(at 8.425 -1.301)
			(size 0.35 2.5)
			(layers "F.Cu" "F.Mask")
			(net 36 "GND")
			(pinfunction "29")
			(pintype "passive")
		)
		(pad "30" smd rect
			(at 8.675 -1.301)
			(size 0.35 2.5)
			(layers "B.Cu" "B.Mask")
			(net 36 "GND")
			(pinfunction "30")
			(pintype "passive")
		)
		(pad "31" smd rect
			(at 8.925 -1.301)
			(size 0.35 2.5)
			(layers "F.Cu" "F.Mask")
			(net 36 "GND")
			(pinfunction "31")
			(pintype "passive")
		)
		(pad "32" smd rect
			(at 9.175 -1.301)
			(size 0.35 2.5)
			(layers "B.Cu" "B.Mask")
			(net 36 "GND")
			(pinfunction "32")
			(pintype "passive")
		)
		(pad "33" smd rect
			(at 9.425 -1.301)
			(size 0.35 2.5)
			(layers "F.Cu" "F.Mask")
			(net 36 "GND")
			(pinfunction "33")
			(pintype "passive")
		)
		(pad "34" smd rect
			(at 9.675 -1.301)
			(size 0.35 2.5)
			(layers "B.Cu" "B.Mask")
			(net 36 "GND")
			(pinfunction "34")
			(pintype "passive")
		)
		(pad "35" smd rect
			(at 9.925 -1.301)
			(size 0.35 2.5)
			(layers "F.Cu" "F.Mask")
			(net 36 "GND")
			(pinfunction "35")
			(pintype "passive")
		)
		(pad "36" smd rect
			(at 10.175 -1.301)
			(size 0.35 2.5)
			(layers "B.Cu" "B.Mask")
			(net 36 "GND")
			(pinfunction "36")
			(pintype "passive")
		)
		(pad "37" smd rect
			(at 10.425 -1.301)
			(size 0.35 2.5)
			(layers "F.Cu" "F.Mask")
			(net 36 "GND")
			(pinfunction "37")
			(pintype "passive")
		)
		(pad "38" smd rect
			(at 10.675 -1.301)
			(size 0.35 2.5)
			(layers "B.Cu" "B.Mask")
			(net 36 "GND")
			(pinfunction "38")
			(pintype "passive")
		)
		(pad "39" smd rect
			(at 10.925 -1.301)
			(size 0.35 2.5)
			(layers "F.Cu" "F.Mask")
			(net 36 "GND")
			(pinfunction "39")
			(pintype "passive")
		)
		(pad "40" smd rect
			(at 11.175 -1.301)
			(size 0.35 2.5)
			(layers "B.Cu" "B.Mask")
			(net 36 "GND")
			(pinfunction "40")
			(pintype "passive")
		)
		(pad "41" smd rect
			(at 11.425 -1.301)
			(size 0.35 2.5)
			(layers "F.Cu" "F.Mask")
			(net 36 "GND")
			(pinfunction "41")
			(pintype "passive")
		)
		(pad "42" smd rect
			(at 11.675 -1.301)
			(size 0.35 2.5)
			(layers "B.Cu" "B.Mask")
			(net 36 "GND")
			(pinfunction "42")
			(pintype "passive")
		)
		(pad "43" smd rect
			(at 11.925 -1.301)
			(size 0.35 2.5)
			(layers "F.Cu" "F.Mask")
			(net 36 "GND")
			(pinfunction "43")
			(pintype "passive")
		)
		(pad "44" smd rect
			(at 12.175 -1.301)
			(size 0.35 2.5)
			(layers "B.Cu" "B.Mask")
			(net 36 "GND")
			(pinfunction "44")
			(pintype "passive")
		)
		(pad "45" smd rect
			(at 12.425 -1.301)
			(size 0.35 2.5)
			(layers "F.Cu" "F.Mask")
			(net 36 "GND")
			(pinfunction "45")
			(pintype "passive")
		)
		(pad "46" smd rect
			(at 12.675 -1.301)
			(size 0.35 2.5)
			(layers "B.Cu" "B.Mask")
			(net 36 "GND")
			(pinfunction "46")
			(pintype "passive")
		)
		(pad "47" smd rect
			(at 12.925 -1.301)
			(size 0.35 2.5)
			(layers "F.Cu" "F.Mask")
			(net 36 "GND")
			(pinfunction "47")
			(pintype "passive")
		)
		(pad "48" smd rect
			(at 13.175 -1.301)
			(size 0.35 2.5)
			(layers "B.Cu" "B.Mask")
			(net 36 "GND")
			(pinfunction "48")
			(pintype "passive")
		)
		(pad "49" smd rect
			(at 13.425 -1.301)
			(size 0.35 2.5)
			(layers "F.Cu" "F.Mask")
			(net 36 "GND")
			(pinfunction "49")
			(pintype "passive")
		)
		(pad "50" smd rect
			(at 13.675 -1.301)
			(size 0.35 2.5)
			(layers "B.Cu" "B.Mask")
			(net 36 "GND")
			(pinfunction "50")
			(pintype "passive")
		)
		(pad "51" smd rect
			(at 13.925 -1.301)
			(size 0.35 2.5)
			(layers "F.Cu" "F.Mask")
			(net 4 "unconnected-(J1-Pad51)")
			(pinfunction "51")
			(pintype "passive+no_connect")
		)
		(pad "52" smd rect
			(at 14.175 -1.301)
			(size 0.35 2.5)
			(layers "B.Cu" "B.Mask")
			(net 5 "unconnected-(J1-Pad52)")
			(pinfunction "52")
			(pintype "passive+no_connect")
		)
		(pad "53" smd rect
			(at 14.425 -1.301)
			(size 0.35 2.5)
			(layers "F.Cu" "F.Mask")
			(net 6 "unconnected-(J1-Pad53)")
			(pinfunction "53")
			(pintype "passive+no_connect")
		)
		(pad "54" smd rect
			(at 14.675 -1.301)
			(size 0.35 2.5)
			(layers "B.Cu" "B.Mask")
			(net 7 "unconnected-(J1-Pad54)")
			(pinfunction "54")
			(pintype "passive+no_connect")
		)
		(pad "55" smd rect
			(at 14.925 -1.301)
			(size 0.35 2.5)
			(layers "F.Cu" "F.Mask")
			(net 8 "unconnected-(J1-Pad55)")
			(pinfunction "55")
			(pintype "passive+no_connect")
		)
		(pad "56" smd rect
			(at 15.175 -1.301)
			(size 0.35 2.5)
			(layers "B.Cu" "B.Mask")
			(net 9 "unconnected-(J1-Pad56)")
			(pinfunction "56")
			(pintype "passive+no_connect")
		)
		(pad "57" smd rect
			(at 15.425 -1.301)
			(size 0.35 2.5)
			(layers "F.Cu" "F.Mask")
			(net 10 "unconnected-(J1-Pad57)")
			(pinfunction "57")
			(pintype "passive+no_connect")
		)
		(pad "58" smd rect
			(at 15.675 -1.301)
			(size 0.35 2.5)
			(layers "B.Cu" "B.Mask")
			(net 11 "unconnected-(J1-Pad58)")
			(pinfunction "58")
			(pintype "passive+no_connect")
		)
		(pad "59" smd rect
			(at 15.925 -1.301)
			(size 0.35 2.5)
			(layers "F.Cu" "F.Mask")
			(net 12 "unconnected-(J1-Pad59)")
			(pinfunction "59")
			(pintype "passive+no_connect")
		)
		(pad "60" smd rect
			(at 16.175 -1.301)
			(size 0.35 2.5)
			(layers "B.Cu" "B.Mask")
			(net 13 "unconnected-(J1-Pad60)")
			(pinfunction "60")
			(pintype "passive+no_connect")
		)
		(pad "61" smd rect
			(at 16.425 -1.301)
			(size 0.35 2.5)
			(layers "F.Cu" "F.Mask")
			(net 14 "unconnected-(J1-Pad61)")
			(pinfunction "61")
			(pintype "passive+no_connect")
		)
		(pad "62" smd rect
			(at 16.675 -1.301)
			(size 0.35 2.5)
			(layers "B.Cu" "B.Mask")
			(net 15 "unconnected-(J1-Pad62)")
			(pinfunction "62")
			(pintype "passive+no_connect")
		)
		(pad "63" smd rect
			(at 16.925 -1.301)
			(size 0.35 2.5)
			(layers "F.Cu" "F.Mask")
			(net 16 "unconnected-(J1-Pad63)")
			(pinfunction "63")
			(pintype "passive+no_connect")
		)
		(pad "64" smd rect
			(at 17.175 -1.301)
			(size 0.35 2.5)
			(layers "B.Cu" "B.Mask")
			(net 17 "unconnected-(J1-Pad64)")
			(pinfunction "64")
			(pintype "passive+no_connect")
		)
		(pad "65" smd rect
			(at 17.425 -1.301)
			(size 0.35 2.5)
			(layers "F.Cu" "F.Mask")
			(net 18 "unconnected-(J1-Pad65)")
			(pinfunction "65")
			(pintype "passive+no_connect")
		)
		(pad "66" smd rect
			(at 17.675 -1.301)
			(size 0.35 2.5)
			(layers "B.Cu" "B.Mask")
			(net 19 "unconnected-(J1-Pad66)")
			(pinfunction "66")
			(pintype "passive+no_connect")
		)
		(pad "67" smd rect
			(at 17.925 -1.301)
			(size 0.35 2.5)
			(layers "F.Cu" "F.Mask")
			(net 20 "unconnected-(J1-Pad67)")
			(pinfunction "67")
			(pintype "passive+no_connect")
		)
		(pad "68" smd rect
			(at 18.175 -1.301)
			(size 0.35 2.5)
			(layers "B.Cu" "B.Mask")
			(net 21 "unconnected-(J1-Pad68)")
			(pinfunction "68")
			(pintype "passive+no_connect")
		)
		(pad "69" smd rect
			(at 18.425 -1.301)
			(size 0.35 2.5)
			(layers "F.Cu" "F.Mask")
			(net 22 "unconnected-(J1-Pad69)")
			(pinfunction "69")
			(pintype "passive+no_connect")
		)
		(pad "70" smd rect
			(at 18.675 -1.301)
			(size 0.35 2.5)
			(layers "B.Cu" "B.Mask")
			(net 23 "unconnected-(J1-Pad70)")
			(pinfunction "70")
			(pintype "passive+no_connect")
		)
		(pad "71" smd rect
			(at 18.925 -1.301)
			(size 0.35 2.5)
			(layers "F.Cu" "F.Mask")
			(net 24 "unconnected-(J1-Pad71)")
			(pinfunction "71")
			(pintype "passive+no_connect")
		)
		(pad "72" smd rect
			(at 19.175 -1.301)
			(size 0.35 2.5)
			(layers "B.Cu" "B.Mask")
			(net 25 "unconnected-(J1-Pad72)")
			(pinfunction "72")
			(pintype "passive+no_connect")
		)
		(pad "73" smd rect
			(at 19.425 -1.301)
			(size 0.35 2.5)
			(layers "F.Cu" "F.Mask")
			(net 26 "unconnected-(J1-Pad73)")
			(pinfunction "73")
			(pintype "passive+no_connect")
		)
		(pad "74" smd rect
			(at 19.675 -1.301)
			(size 0.35 2.5)
			(layers "B.Cu" "B.Mask")
			(net 27 "unconnected-(J1-Pad74)")
			(pinfunction "74")
			(pintype "passive+no_connect")
		)
		(pad "75" smd rect
			(at 19.925 -1.301)
			(size 0.35 2.5)
			(layers "F.Cu" "F.Mask")
			(net 28 "unconnected-(J1-Pad75)")
			(pinfunction "75")
			(pintype "passive+no_connect")
		)
		(pad "76" smd rect
			(at 20.175 -1.301)
			(size 0.35 2.5)
			(layers "B.Cu" "B.Mask")
			(net 29 "unconnected-(J1-Pad76)")
			(pinfunction "76")
			(pintype "passive+no_connect")
		)
		(pad "77" smd rect
			(at 20.425 -1.301)
			(size 0.35 2.5)
			(layers "F.Cu" "F.Mask")
			(net 30 "unconnected-(J1-Pad77)")
			(pinfunction "77")
			(pintype "passive+no_connect")
		)
		(pad "78" smd rect
			(at 20.675 -1.301)
			(size 0.35 2.5)
			(layers "B.Cu" "B.Mask")
			(net 31 "unconnected-(J1-Pad78)")
			(pinfunction "78")
			(pintype "passive+no_connect")
		)
		(pad "79" smd rect
			(at 20.925 -1.301)
			(size 0.35 2.5)
			(layers "F.Cu" "F.Mask")
			(net 32 "unconnected-(J1-Pad79)")
			(pinfunction "79")
			(pintype "passive+no_connect")
		)
		(pad "80" smd rect
			(at 21.175 -1.301)
			(size 0.35 2.5)
			(layers "B.Cu" "B.Mask")
			(net 33 "unconnected-(J1-Pad80)")
			(pinfunction "80")
			(pintype "passive+no_connect")
		)
		(pad "81" smd rect
			(at 21.425 -1.301)
			(size 0.35 2.5)
			(layers "F.Cu" "F.Mask")
			(net 34 "unconnected-(J1-Pad81)")
			(pinfunction "81")
			(pintype "passive+no_connect")
		)
		(pad "82" smd rect
			(at 21.675 -1.301)
			(size 0.35 2.5)
			(layers "B.Cu" "B.Mask")
			(net 35 "unconnected-(J1-Pad82)")
			(pinfunction "82")
			(pintype "passive+no_connect")
		)
		(pad "83" smd rect
			(at 21.925 -1.301)
			(size 0.35 2.5)
			(layers "F.Cu" "F.Mask")
			(net 37 "unconnected-(J1-Pad83)")
			(pinfunction "83")
			(pintype "passive+no_connect")
		)
		(pad "84" smd rect
			(at 22.175 -1.301)
			(size 0.35 2.5)
			(layers "B.Cu" "B.Mask")
			(net 38 "unconnected-(J1-Pad84)")
			(pinfunction "84")
			(pintype "passive+no_connect")
		)
		(pad "85" smd rect
			(at 22.425 -1.301)
			(size 0.35 2.5)
			(layers "F.Cu" "F.Mask")
			(net 39 "unconnected-(J1-Pad85)")
			(pinfunction "85")
			(pintype "passive+no_connect")
		)
		(pad "86" smd rect
			(at 22.675 -1.301)
			(size 0.35 2.5)
			(layers "B.Cu" "B.Mask")
			(net 40 "unconnected-(J1-Pad86)")
			(pinfunction "86")
			(pintype "passive+no_connect")
		)
		(pad "87" smd rect
			(at 22.925 -1.301)
			(size 0.35 2.5)
			(layers "F.Cu" "F.Mask")
			(net 41 "unconnected-(J1-Pad87)")
			(pinfunction "87")
			(pintype "passive+no_connect")
		)
		(pad "88" smd rect
			(at 23.175 -1.301)
			(size 0.35 2.5)
			(layers "B.Cu" "B.Mask")
			(net 42 "unconnected-(J1-Pad88)")
			(pinfunction "88")
			(pintype "passive+no_connect")
		)
		(pad "89" smd rect
			(at 23.425 -1.301)
			(size 0.35 2.5)
			(layers "F.Cu" "F.Mask")
			(net 43 "unconnected-(J1-Pad89)")
			(pinfunction "89")
			(pintype "passive+no_connect")
		)
		(pad "90" smd rect
			(at 23.675 -1.301)
			(size 0.35 2.5)
			(layers "B.Cu" "B.Mask")
			(net 44 "unconnected-(J1-Pad90)")
			(pinfunction "90")
			(pintype "passive+no_connect")
		)
		(pad "91" smd rect
			(at 23.925 -1.301)
			(size 0.35 2.5)
			(layers "F.Cu" "F.Mask")
			(net 45 "unconnected-(J1-Pad91)")
			(pinfunction "91")
			(pintype "passive+no_connect")
		)
		(pad "92" smd rect
			(at 24.175 -1.301)
			(size 0.35 2.5)
			(layers "B.Cu" "B.Mask")
			(net 46 "unconnected-(J1-Pad92)")
			(pinfunction "92")
			(pintype "passive+no_connect")
		)
		(pad "93" smd rect
			(at 24.425 -1.301)
			(size 0.35 2.5)
			(layers "F.Cu" "F.Mask")
			(net 188 "VDD2")
			(pinfunction "93")
			(pintype "passive")
		)
		(pad "94" smd rect
			(at 24.675 -1.301)
			(size 0.35 2.5)
			(layers "B.Cu" "B.Mask")
			(net 47 "unconnected-(J1-Pad94)")
			(pinfunction "94")
			(pintype "passive+no_connect")
		)
		(pad "95" smd rect
			(at 24.925 -1.301)
			(size 0.35 2.5)
			(layers "F.Cu" "F.Mask")
			(net 188 "VDD2")
			(pinfunction "95")
			(pintype "passive")
		)
		(pad "96" smd rect
			(at 25.175 -1.301)
			(size 0.35 2.5)
			(layers "B.Cu" "B.Mask")
			(net 48 "unconnected-(J1-Pad96)")
			(pinfunction "96")
			(pintype "passive+no_connect")
		)
		(pad "97" smd rect
			(at 25.425 -1.301)
			(size 0.35 2.5)
			(layers "F.Cu" "F.Mask")
			(net 188 "VDD2")
			(pinfunction "97")
			(pintype "passive")
		)
		(pad "98" smd rect
			(at 25.675 -1.301)
			(size 0.35 2.5)
			(layers "B.Cu" "B.Mask")
			(net 49 "unconnected-(J1-Pad98)")
			(pinfunction "98")
			(pintype "passive+no_connect")
		)
		(pad "99" smd rect
			(at 25.925 -1.301)
			(size 0.35 2.5)
			(layers "F.Cu" "F.Mask")
			(net 188 "VDD2")
			(pinfunction "99")
			(pintype "passive")
		)
		(pad "100" smd rect
			(at 26.175 -1.301)
			(size 0.35 2.5)
			(layers "B.Cu" "B.Mask")
			(net 50 "unconnected-(J1-Pad100)")
			(pinfunction "100")
			(pintype "passive+no_connect")
		)
		(pad "101" smd rect
			(at 26.425 -1.301)
			(size 0.35 2.5)
			(layers "F.Cu" "F.Mask")
			(net 188 "VDD2")
			(pinfunction "101")
			(pintype "passive")
		)
		(pad "102" smd rect
			(at 26.675 -1.301)
			(size 0.35 2.5)
			(layers "B.Cu" "B.Mask")
			(net 51 "unconnected-(J1-Pad102)")
			(pinfunction "102")
			(pintype "passive+no_connect")
		)
		(pad "103" smd rect
			(at 26.925 -1.301)
			(size 0.35 2.5)
			(layers "F.Cu" "F.Mask")
			(net 188 "VDD2")
			(pinfunction "103")
			(pintype "passive")
		)
		(pad "104" smd rect
			(at 27.175 -1.301)
			(size 0.35 2.5)
			(layers "B.Cu" "B.Mask")
			(net 52 "unconnected-(J1-Pad104)")
			(pinfunction "104")
			(pintype "passive+no_connect")
		)
		(pad "105" smd rect
			(at 27.425 -1.301)
			(size 0.35 2.5)
			(layers "F.Cu" "F.Mask")
			(net 188 "VDD2")
			(pinfunction "105")
			(pintype "passive")
		)
		(pad "106" smd rect
			(at 27.675 -1.301)
			(size 0.35 2.5)
			(layers "B.Cu" "B.Mask")
			(net 53 "unconnected-(J1-Pad106)")
			(pinfunction "106")
			(pintype "passive+no_connect")
		)
		(pad "107" smd rect
			(at 27.925 -1.301)
			(size 0.35 2.5)
			(layers "F.Cu" "F.Mask")
			(net 188 "VDD2")
			(pinfunction "107")
			(pintype "passive")
		)
		(pad "108" smd rect
			(at 28.175 -1.301)
			(size 0.35 2.5)
			(layers "B.Cu" "B.Mask")
			(net 54 "unconnected-(J1-Pad108)")
			(pinfunction "108")
			(pintype "passive+no_connect")
		)
		(pad "109" smd rect
			(at 28.425 -1.301)
			(size 0.35 2.5)
			(layers "F.Cu" "F.Mask")
			(net 55 "unconnected-(J1-Pad109)")
			(pinfunction "109")
			(pintype "passive+no_connect")
		)
		(pad "110" smd rect
			(at 28.675 -1.301)
			(size 0.35 2.5)
			(layers "B.Cu" "B.Mask")
			(net 56 "unconnected-(J1-Pad110)")
			(pinfunction "110")
			(pintype "passive+no_connect")
		)
		(pad "111" smd rect
			(at 28.925 -1.301)
			(size 0.35 2.5)
			(layers "F.Cu" "F.Mask")
			(net 57 "unconnected-(J1-Pad111)")
			(pinfunction "111")
			(pintype "passive+no_connect")
		)
		(pad "112" smd rect
			(at 29.175 -1.301)
			(size 0.35 2.5)
			(layers "B.Cu" "B.Mask")
			(net 58 "unconnected-(J1-Pad112)")
			(pinfunction "112")
			(pintype "passive+no_connect")
		)
		(pad "113" smd rect
			(at 29.425 -1.301)
			(size 0.35 2.5)
			(layers "F.Cu" "F.Mask")
			(net 59 "unconnected-(J1-Pad113)")
			(pinfunction "113")
			(pintype "passive+no_connect")
		)
		(pad "114" smd rect
			(at 29.675 -1.301)
			(size 0.35 2.5)
			(layers "B.Cu" "B.Mask")
			(net 60 "unconnected-(J1-Pad114)")
			(pinfunction "114")
			(pintype "passive+no_connect")
		)
		(pad "115" smd rect
			(at 29.925 -1.301)
			(size 0.35 2.5)
			(layers "F.Cu" "F.Mask")
			(net 61 "unconnected-(J1-Pad115)")
			(pinfunction "115")
			(pintype "passive+no_connect")
		)
		(pad "116" smd rect
			(at 30.175 -1.301)
			(size 0.35 2.5)
			(layers "B.Cu" "B.Mask")
			(net 187 "VDD1")
			(pinfunction "116")
			(pintype "passive")
		)
		(pad "117" smd rect
			(at 30.425 -1.301)
			(size 0.35 2.5)
			(layers "F.Cu" "F.Mask")
			(net 62 "unconnected-(J1-Pad117)")
			(pinfunction "117")
			(pintype "passive+no_connect")
		)
		(pad "118" smd rect
			(at 30.675 -1.301)
			(size 0.35 2.5)
			(layers "B.Cu" "B.Mask")
			(net 187 "VDD1")
			(pinfunction "118")
			(pintype "passive")
		)
		(pad "119" smd rect
			(at 30.925 -1.301)
			(size 0.35 2.5)
			(layers "F.Cu" "F.Mask")
			(net 63 "unconnected-(J1-Pad119)")
			(pinfunction "119")
			(pintype "passive+no_connect")
		)
		(pad "120" smd rect
			(at 31.175 -1.301)
			(size 0.35 2.5)
			(layers "B.Cu" "B.Mask")
			(net 187 "VDD1")
			(pinfunction "120")
			(pintype "passive")
		)
		(pad "121" smd rect
			(at 31.425 -1.301)
			(size 0.35 2.5)
			(layers "F.Cu" "F.Mask")
			(net 64 "unconnected-(J1-Pad121)")
			(pinfunction "121")
			(pintype "passive+no_connect")
		)
		(pad "122" smd rect
			(at 31.675 -1.301)
			(size 0.35 2.5)
			(layers "B.Cu" "B.Mask")
			(net 187 "VDD1")
			(pinfunction "122")
			(pintype "passive")
		)
		(pad "123" smd rect
			(at 31.925 -1.301)
			(size 0.35 2.5)
			(layers "F.Cu" "F.Mask")
			(net 65 "unconnected-(J1-Pad123)")
			(pinfunction "123")
			(pintype "passive+no_connect")
		)
		(pad "124" smd rect
			(at 32.173 -1.301)
			(size 0.35 2.5)
			(layers "B.Cu" "B.Mask")
			(net 187 "VDD1")
			(pinfunction "124")
			(pintype "passive")
		)
		(pad "125" smd rect
			(at 32.423 -1.301)
			(size 0.35 2.5)
			(layers "F.Cu" "F.Mask")
			(net 66 "unconnected-(J1-Pad125)")
			(pinfunction "125")
			(pintype "passive+no_connect")
		)
		(pad "126" smd rect
			(at 32.673 -1.301)
			(size 0.35 2.5)
			(layers "B.Cu" "B.Mask")
			(net 189 "VDDQ")
			(pinfunction "126")
			(pintype "passive")
		)
		(pad "127" smd rect
			(at 32.923 -1.301)
			(size 0.35 2.5)
			(layers "F.Cu" "F.Mask")
			(net 246 "SDA")
			(pinfunction "127")
			(pintype "passive")
		)
		(pad "128" smd rect
			(at 33.173 -1.301)
			(size 0.35 2.5)
			(layers "B.Cu" "B.Mask")
			(net 189 "VDDQ")
			(pinfunction "128")
			(pintype "passive")
		)
		(pad "129" smd rect
			(at 33.423 -1.301)
			(size 0.35 2.5)
			(layers "F.Cu" "F.Mask")
			(net 247 "SCL")
			(pinfunction "129")
			(pintype "passive")
		)
		(pad "130" smd rect
			(at 33.673 -1.301)
			(size 0.35 2.5)
			(layers "B.Cu" "B.Mask")
			(net 189 "VDDQ")
			(pinfunction "130")
			(pintype "passive")
		)
		(pad "131" smd rect
			(at 33.923 -1.301)
			(size 0.35 2.5)
			(layers "F.Cu" "F.Mask")
			(net 67 "unconnected-(J1-Pad131)")
			(pinfunction "131")
			(pintype "passive+no_connect")
		)
		(pad "132" smd rect
			(at 34.173 -1.301)
			(size 0.35 2.5)
			(layers "B.Cu" "B.Mask")
			(net 68 "unconnected-(J1-Pad132)")
			(pinfunction "132")
			(pintype "passive+no_connect")
		)
		(pad "133" smd rect
			(at 34.423 -1.301)
			(size 0.35 2.5)
			(layers "F.Cu" "F.Mask")
			(net 69 "unconnected-(J1-Pad133)")
			(pinfunction "133")
			(pintype "passive+no_connect")
		)
		(pad "134" smd rect
			(at 34.673 -1.301)
			(size 0.35 2.5)
			(layers "B.Cu" "B.Mask")
			(net 70 "unconnected-(J1-Pad134)")
			(pinfunction "134")
			(pintype "passive+no_connect")
		)
		(pad "135" smd rect
			(at 34.923 -1.301)
			(size 0.35 2.5)
			(layers "F.Cu" "F.Mask")
			(net 71 "unconnected-(J1-Pad135)")
			(pinfunction "135")
			(pintype "passive+no_connect")
		)
		(pad "136" smd rect
			(at 35.173 -1.301)
			(size 0.35 2.5)
			(layers "B.Cu" "B.Mask")
			(net 72 "unconnected-(J1-Pad136)")
			(pinfunction "136")
			(pintype "passive+no_connect")
		)
		(pad "137" smd rect
			(at 35.423 -1.301)
			(size 0.35 2.5)
			(layers "F.Cu" "F.Mask")
			(net 73 "unconnected-(J1-Pad137)")
			(pinfunction "137")
			(pintype "passive+no_connect")
		)
		(pad "138" smd rect
			(at 35.673 -1.301)
			(size 0.35 2.5)
			(layers "B.Cu" "B.Mask")
			(net 74 "unconnected-(J1-Pad138)")
			(pinfunction "138")
			(pintype "passive+no_connect")
		)
		(pad "139" smd rect
			(at 35.923 -1.301)
			(size 0.35 2.5)
			(layers "F.Cu" "F.Mask")
			(net 75 "unconnected-(J1-Pad139)")
			(pinfunction "139")
			(pintype "passive+no_connect")
		)
		(pad "140" smd rect
			(at 36.173 -1.301)
			(size 0.35 2.5)
			(layers "B.Cu" "B.Mask")
			(net 76 "unconnected-(J1-Pad140)")
			(pinfunction "140")
			(pintype "passive+no_connect")
		)
		(pad "141" smd rect
			(at 36.423 -1.301)
			(size 0.35 2.5)
			(layers "F.Cu" "F.Mask")
			(net 77 "unconnected-(J1-Pad141)")
			(pinfunction "141")
			(pintype "passive+no_connect")
		)
		(pad "142" smd rect
			(at 36.673 -1.301)
			(size 0.35 2.5)
			(layers "B.Cu" "B.Mask")
			(net 78 "unconnected-(J1-Pad142)")
			(pinfunction "142")
			(pintype "passive+no_connect")
		)
		(pad "143" smd rect
			(at 36.923 -1.301)
			(size 0.35 2.5)
			(layers "F.Cu" "F.Mask")
			(net 79 "unconnected-(J1-Pad143)")
			(pinfunction "143")
			(pintype "passive+no_connect")
		)
		(pad "144" smd rect
			(at 37.173 -1.301)
			(size 0.35 2.5)
			(layers "B.Cu" "B.Mask")
			(net 80 "unconnected-(J1-Pad144)")
			(pinfunction "144")
			(pintype "passive+no_connect")
		)
		(pad "145" smd rect
			(at 39.423 -1.301)
			(size 0.35 2.5)
			(layers "F.Cu" "F.Mask")
			(net 81 "unconnected-(J1-Pad145)")
			(pinfunction "145")
			(pintype "passive+no_connect")
		)
		(pad "146" smd rect
			(at 39.673 -1.301)
			(size 0.35 2.5)
			(layers "B.Cu" "B.Mask")
			(net 82 "unconnected-(J1-Pad146)")
			(pinfunction "146")
			(pintype "passive+no_connect")
		)
		(pad "147" smd rect
			(at 39.923 -1.301)
			(size 0.35 2.5)
			(layers "F.Cu" "F.Mask")
			(net 83 "unconnected-(J1-Pad147)")
			(pinfunction "147")
			(pintype "passive+no_connect")
		)
		(pad "148" smd rect
			(at 40.173 -1.301)
			(size 0.35 2.5)
			(layers "B.Cu" "B.Mask")
			(net 84 "unconnected-(J1-Pad148)")
			(pinfunction "148")
			(pintype "passive+no_connect")
		)
		(pad "149" smd rect
			(at 40.423 -1.301)
			(size 0.35 2.5)
			(layers "F.Cu" "F.Mask")
			(net 85 "unconnected-(J1-Pad149)")
			(pinfunction "149")
			(pintype "passive+no_connect")
		)
		(pad "150" smd rect
			(at 40.673 -1.301)
			(size 0.35 2.5)
			(layers "B.Cu" "B.Mask")
			(net 86 "unconnected-(J1-Pad150)")
			(pinfunction "150")
			(pintype "passive+no_connect")
		)
		(pad "151" smd rect
			(at 40.923 -1.301)
			(size 0.35 2.5)
			(layers "F.Cu" "F.Mask")
			(net 87 "unconnected-(J1-Pad151)")
			(pinfunction "151")
			(pintype "passive+no_connect")
		)
		(pad "152" smd rect
			(at 41.173 -1.301)
			(size 0.35 2.5)
			(layers "B.Cu" "B.Mask")
			(net 88 "unconnected-(J1-Pad152)")
			(pinfunction "152")
			(pintype "passive+no_connect")
		)
		(pad "153" smd rect
			(at 41.423 -1.301)
			(size 0.35 2.5)
			(layers "F.Cu" "F.Mask")
			(net 89 "unconnected-(J1-Pad153)")
			(pinfunction "153")
			(pintype "passive+no_connect")
		)
		(pad "154" smd rect
			(at 41.673 -1.301)
			(size 0.35 2.5)
			(layers "B.Cu" "B.Mask")
			(net 36 "GND")
			(pinfunction "154")
			(pintype "passive")
		)
		(pad "155" smd rect
			(at 41.923 -1.301)
			(size 0.35 2.5)
			(layers "F.Cu" "F.Mask")
			(net 90 "unconnected-(J1-Pad155)")
			(pinfunction "155")
			(pintype "passive+no_connect")
		)
		(pad "156" smd rect
			(at 42.173 -1.301)
			(size 0.35 2.5)
			(layers "B.Cu" "B.Mask")
			(net 221 "CA5_A")
			(pinfunction "156")
			(pintype "passive")
		)
		(pad "157" smd rect
			(at 42.423 -1.301)
			(size 0.35 2.5)
			(layers "F.Cu" "F.Mask")
			(net 91 "unconnected-(J1-Pad157)")
			(pinfunction "157")
			(pintype "passive+no_connect")
		)
		(pad "158" smd rect
			(at 42.673 -1.301)
			(size 0.35 2.5)
			(layers "B.Cu" "B.Mask")
			(net 220 "CA4_A")
			(pinfunction "158")
			(pintype "passive")
		)
		(pad "159" smd rect
			(at 42.923 -1.301)
			(size 0.35 2.5)
			(layers "F.Cu" "F.Mask")
			(net 92 "unconnected-(J1-Pad159)")
			(pinfunction "159")
			(pintype "passive+no_connect")
		)
		(pad "160" smd rect
			(at 43.173 -1.301)
			(size 0.35 2.5)
			(layers "B.Cu" "B.Mask")
			(net 219 "CA3_A")
			(pinfunction "160")
			(pintype "passive")
		)
		(pad "161" smd rect
			(at 43.423 -1.301)
			(size 0.35 2.5)
			(layers "F.Cu" "F.Mask")
			(net 36 "GND")
			(pinfunction "161")
			(pintype "passive")
		)
		(pad "162" smd rect
			(at 43.673 -1.301)
			(size 0.35 2.5)
			(layers "B.Cu" "B.Mask")
			(net 218 "CA2_A")
			(pinfunction "162")
			(pintype "passive")
		)
		(pad "163" smd rect
			(at 43.923 -1.301)
			(size 0.35 2.5)
			(layers "F.Cu" "F.Mask")
			(net 217 "DQ11_A")
			(pinfunction "163")
			(pintype "passive")
		)
		(pad "164" smd rect
			(at 44.173 -1.301)
			(size 0.35 2.5)
			(layers "B.Cu" "B.Mask")
			(net 214 "CK_C_A")
			(pinfunction "164")
			(pintype "passive")
		)
		(pad "165" smd rect
			(at 44.423 -1.301)
			(size 0.35 2.5)
			(layers "F.Cu" "F.Mask")
			(net 215 "DQ10_A")
			(pinfunction "165")
			(pintype "passive")
		)
		(pad "166" smd rect
			(at 44.673 -1.301)
			(size 0.35 2.5)
			(layers "B.Cu" "B.Mask")
			(net 216 "CK_T_A")
			(pinfunction "166")
			(pintype "passive")
		)
		(pad "167" smd rect
			(at 44.923 -1.301)
			(size 0.35 2.5)
			(layers "F.Cu" "F.Mask")
			(net 213 "DQ09_A")
			(pinfunction "167")
			(pintype "passive")
		)
		(pad "168" smd rect
			(at 45.173 -1.301)
			(size 0.35 2.5)
			(layers "B.Cu" "B.Mask")
			(net 36 "GND")
			(pinfunction "168")
			(pintype "passive")
		)
		(pad "169" smd rect
			(at 45.423 -1.301)
			(size 0.35 2.5)
			(layers "F.Cu" "F.Mask")
			(net 212 "DQ08_A")
			(pinfunction "169")
			(pintype "passive")
		)
		(pad "170" smd rect
			(at 45.673 -1.301)
			(size 0.35 2.5)
			(layers "B.Cu" "B.Mask")
			(net 93 "unconnected-(J1-Pad170)")
			(pinfunction "170")
			(pintype "passive+no_connect")
		)
		(pad "171" smd rect
			(at 45.923 -1.301)
			(size 0.35 2.5)
			(layers "F.Cu" "F.Mask")
			(net 211 "DMI_1A")
			(pinfunction "171")
			(pintype "passive")
		)
		(pad "172" smd rect
			(at 46.173 -1.301)
			(size 0.35 2.5)
			(layers "B.Cu" "B.Mask")
			(net 94 "unconnected-(J1-Pad172)")
			(pinfunction "172")
			(pintype "passive+no_connect")
		)
		(pad "173" smd rect
			(at 46.423 -1.301)
			(size 0.35 2.5)
			(layers "F.Cu" "F.Mask")
			(net 210 "DQ_S1_CA")
			(pinfunction "173")
			(pintype "passive")
		)
		(pad "174" smd rect
			(at 46.673 -1.301)
			(size 0.35 2.5)
			(layers "B.Cu" "B.Mask")
			(net 95 "unconnected-(J1-Pad174)")
			(pinfunction "174")
			(pintype "passive+no_connect")
		)
		(pad "175" smd rect
			(at 46.923 -1.301)
			(size 0.35 2.5)
			(layers "F.Cu" "F.Mask")
			(net 209 "DQ_S1_TA")
			(pinfunction "175")
			(pintype "passive")
		)
		(pad "176" smd rect
			(at 47.173 -1.301)
			(size 0.35 2.5)
			(layers "B.Cu" "B.Mask")
			(net 96 "unconnected-(J1-Pad176)")
			(pinfunction "176")
			(pintype "passive+no_connect")
		)
		(pad "177" smd rect
			(at 47.423 -1.301)
			(size 0.35 2.5)
			(layers "F.Cu" "F.Mask")
			(net 36 "GND")
			(pinfunction "177")
			(pintype "passive")
		)
		(pad "178" smd rect
			(at 47.673 -1.301)
			(size 0.35 2.5)
			(layers "B.Cu" "B.Mask")
			(net 97 "unconnected-(J1-Pad178)")
			(pinfunction "178")
			(pintype "passive+no_connect")
		)
		(pad "179" smd rect
			(at 47.923 -1.301)
			(size 0.35 2.5)
			(layers "F.Cu" "F.Mask")
			(net 208 "DQ15_A")
			(pinfunction "179")
			(pintype "passive")
		)
		(pad "180" smd rect
			(at 48.173 -1.301)
			(size 0.35 2.5)
			(layers "B.Cu" "B.Mask")
			(net 98 "unconnected-(J1-Pad180)")
			(pinfunction "180")
			(pintype "passive+no_connect")
		)
		(pad "181" smd rect
			(at 48.423 -1.301)
			(size 0.35 2.5)
			(layers "F.Cu" "F.Mask")
			(net 207 "DQ14_A")
			(pinfunction "181")
			(pintype "passive")
		)
		(pad "182" smd rect
			(at 48.673 -1.301)
			(size 0.35 2.5)
			(layers "B.Cu" "B.Mask")
			(net 99 "unconnected-(J1-Pad182)")
			(pinfunction "182")
			(pintype "passive+no_connect")
		)
		(pad "183" smd rect
			(at 48.923 -1.301)
			(size 0.35 2.5)
			(layers "F.Cu" "F.Mask")
			(net 206 "DQ13_A")
			(pinfunction "183")
			(pintype "passive")
		)
		(pad "184" smd rect
			(at 49.173 -1.301)
			(size 0.35 2.5)
			(layers "B.Cu" "B.Mask")
			(net 36 "GND")
			(pinfunction "184")
			(pintype "passive")
		)
		(pad "185" smd rect
			(at 49.423 -1.301)
			(size 0.35 2.5)
			(layers "F.Cu" "F.Mask")
			(net 205 "DQ12_A")
			(pinfunction "185")
			(pintype "passive")
		)
		(pad "186" smd rect
			(at 49.673 -1.301)
			(size 0.35 2.5)
			(layers "B.Cu" "B.Mask")
			(net 230 "RESET_N")
			(pinfunction "186")
			(pintype "passive")
		)
		(pad "187" smd rect
			(at 49.923 -1.301)
			(size 0.35 2.5)
			(layers "F.Cu" "F.Mask")
			(net 204 "DQ04_A")
			(pinfunction "187")
			(pintype "passive")
		)
		(pad "188" smd rect
			(at 50.173 -1.301)
			(size 0.35 2.5)
			(layers "B.Cu" "B.Mask")
			(net 100 "unconnected-(J1-Pad188)")
			(pinfunction "188")
			(pintype "passive+no_connect")
		)
		(pad "189" smd rect
			(at 50.423 -1.301)
			(size 0.35 2.5)
			(layers "F.Cu" "F.Mask")
			(net 203 "DQ05_A")
			(pinfunction "189")
			(pintype "passive")
		)
		(pad "190" smd rect
			(at 50.673 -1.301)
			(size 0.35 2.5)
			(layers "B.Cu" "B.Mask")
			(net 101 "unconnected-(J1-Pad190)")
			(pinfunction "190")
			(pintype "passive+no_connect")
		)
		(pad "191" smd rect
			(at 50.923 -1.301)
			(size 0.35 2.5)
			(layers "F.Cu" "F.Mask")
			(net 202 "DQ06_A")
			(pinfunction "191")
			(pintype "passive")
		)
		(pad "192" smd rect
			(at 51.173 -1.301)
			(size 0.35 2.5)
			(layers "B.Cu" "B.Mask")
			(net 229 "ODT_CA_A")
			(pinfunction "192")
			(pintype "passive")
		)
		(pad "193" smd rect
			(at 51.423 -1.301)
			(size 0.35 2.5)
			(layers "F.Cu" "F.Mask")
			(net 198 "DQ07_A")
			(pinfunction "193")
			(pintype "passive")
		)
		(pad "194" smd rect
			(at 51.673 -1.301)
			(size 0.35 2.5)
			(layers "B.Cu" "B.Mask")
			(net 200 "CS0_A")
			(pinfunction "194")
			(pintype "passive")
		)
		(pad "195" smd rect
			(at 51.923 -1.301)
			(size 0.35 2.5)
			(layers "F.Cu" "F.Mask")
			(net 36 "GND")
			(pinfunction "195")
			(pintype "passive")
		)
		(pad "196" smd rect
			(at 52.173 -1.301)
			(size 0.35 2.5)
			(layers "B.Cu" "B.Mask")
			(net 199 "CKE0_A")
			(pinfunction "196")
			(pintype "passive")
		)
		(pad "197" smd rect
			(at 52.423 -1.301)
			(size 0.35 2.5)
			(layers "F.Cu" "F.Mask")
			(net 201 "DMI_0A")
			(pinfunction "197")
			(pintype "passive")
		)
		(pad "198" smd rect
			(at 52.673 -1.301)
			(size 0.35 2.5)
			(layers "B.Cu" "B.Mask")
			(net 102 "unconnected-(J1-Pad198)")
			(pinfunction "198")
			(pintype "passive+no_connect")
		)
		(pad "199" smd rect
			(at 52.923 -1.301)
			(size 0.35 2.5)
			(layers "F.Cu" "F.Mask")
			(net 197 "DQ_S0_CA")
			(pinfunction "199")
			(pintype "passive")
		)
		(pad "200" smd rect
			(at 53.173 -1.301)
			(size 0.35 2.5)
			(layers "B.Cu" "B.Mask")
			(net 36 "GND")
			(pinfunction "200")
			(pintype "passive")
		)
		(pad "201" smd rect
			(at 53.423 -1.301)
			(size 0.35 2.5)
			(layers "F.Cu" "F.Mask")
			(net 196 "DQ_S0_TA")
			(pinfunction "201")
			(pintype "passive")
		)
		(pad "202" smd rect
			(at 53.673 -1.301)
			(size 0.35 2.5)
			(layers "B.Cu" "B.Mask")
			(net 103 "unconnected-(J1-Pad202)")
			(pinfunction "202")
			(pintype "passive+no_connect")
		)
		(pad "203" smd rect
			(at 53.923 -1.301)
			(size 0.35 2.5)
			(layers "F.Cu" "F.Mask")
			(net 190 "DQ00_A")
			(pinfunction "203")
			(pintype "passive")
		)
		(pad "204" smd rect
			(at 54.173 -1.301)
			(size 0.35 2.5)
			(layers "B.Cu" "B.Mask")
			(net 192 "CA0_A")
			(pinfunction "204")
			(pintype "passive")
		)
		(pad "205" smd rect
			(at 54.423 -1.301)
			(size 0.35 2.5)
			(layers "F.Cu" "F.Mask")
			(net 191 "DQ01_A")
			(pinfunction "205")
			(pintype "passive")
		)
		(pad "206" smd rect
			(at 54.673 -1.301)
			(size 0.35 2.5)
			(layers "B.Cu" "B.Mask")
			(net 194 "CA1_A")
			(pinfunction "206")
			(pintype "passive")
		)
		(pad "207" smd rect
			(at 54.923 -1.301)
			(size 0.35 2.5)
			(layers "F.Cu" "F.Mask")
			(net 193 "DQ02_A")
			(pinfunction "207")
			(pintype "passive")
		)
		(pad "208" smd rect
			(at 55.173 -1.301)
			(size 0.35 2.5)
			(layers "B.Cu" "B.Mask")
			(net 104 "unconnected-(J1-Pad208)")
			(pinfunction "208")
			(pintype "passive+no_connect")
		)
		(pad "209" smd rect
			(at 55.423 -1.301)
			(size 0.35 2.5)
			(layers "F.Cu" "F.Mask")
			(net 195 "DQ03_A")
			(pinfunction "209")
			(pintype "passive")
		)
		(pad "210" smd rect
			(at 55.673 -1.301)
			(size 0.35 2.5)
			(layers "B.Cu" "B.Mask")
			(net 36 "GND")
			(pinfunction "210")
			(pintype "passive")
		)
		(pad "211" smd rect
			(at 55.923 -1.301)
			(size 0.35 2.5)
			(layers "F.Cu" "F.Mask")
			(net 36 "GND")
			(pinfunction "211")
			(pintype "passive")
		)
		(pad "212" smd rect
			(at 56.173 -1.301)
			(size 0.35 2.5)
			(layers "B.Cu" "B.Mask")
			(net 105 "unconnected-(J1-Pad212)")
			(pinfunction "212")
			(pintype "passive+no_connect")
		)
		(pad "213" smd rect
			(at 56.423 -1.301)
			(size 0.35 2.5)
			(layers "F.Cu" "F.Mask")
			(net 106 "unconnected-(J1-Pad213)")
			(pinfunction "213")
			(pintype "passive+no_connect")
		)
		(pad "214" smd rect
			(at 56.673 -1.301)
			(size 0.35 2.5)
			(layers "B.Cu" "B.Mask")
			(net 107 "unconnected-(J1-Pad214)")
			(pinfunction "214")
			(pintype "passive+no_connect")
		)
		(pad "215" smd rect
			(at 56.923 -1.301)
			(size 0.35 2.5)
			(layers "F.Cu" "F.Mask")
			(net 108 "unconnected-(J1-Pad215)")
			(pinfunction "215")
			(pintype "passive+no_connect")
		)
		(pad "216" smd rect
			(at 57.173 -1.301)
			(size 0.35 2.5)
			(layers "B.Cu" "B.Mask")
			(net 109 "unconnected-(J1-Pad216)")
			(pinfunction "216")
			(pintype "passive+no_connect")
		)
		(pad "217" smd rect
			(at 57.423 -1.301)
			(size 0.35 2.5)
			(layers "F.Cu" "F.Mask")
			(net 110 "unconnected-(J1-Pad217)")
			(pinfunction "217")
			(pintype "passive+no_connect")
		)
		(pad "218" smd rect
			(at 57.673 -1.301)
			(size 0.35 2.5)
			(layers "B.Cu" "B.Mask")
			(net 111 "unconnected-(J1-Pad218)")
			(pinfunction "218")
			(pintype "passive+no_connect")
		)
		(pad "219" smd rect
			(at 57.923 -1.301)
			(size 0.35 2.5)
			(layers "F.Cu" "F.Mask")
			(net 112 "unconnected-(J1-Pad219)")
			(pinfunction "219")
			(pintype "passive+no_connect")
		)
		(pad "220" smd rect
			(at 58.173 -1.301)
			(size 0.35 2.5)
			(layers "B.Cu" "B.Mask")
			(net 113 "unconnected-(J1-Pad220)")
			(pinfunction "220")
			(pintype "passive+no_connect")
		)
		(pad "221" smd rect
			(at 58.423 -1.301)
			(size 0.35 2.5)
			(layers "F.Cu" "F.Mask")
			(net 114 "unconnected-(J1-Pad221)")
			(pinfunction "221")
			(pintype "passive+no_connect")
		)
		(pad "222" smd rect
			(at 58.673 -1.301)
			(size 0.35 2.5)
			(layers "B.Cu" "B.Mask")
			(net 115 "unconnected-(J1-Pad222)")
			(pinfunction "222")
			(pintype "passive+no_connect")
		)
		(pad "223" smd rect
			(at 58.923 -1.301)
			(size 0.35 2.5)
			(layers "F.Cu" "F.Mask")
			(net 116 "unconnected-(J1-Pad223)")
			(pinfunction "223")
			(pintype "passive+no_connect")
		)
		(pad "224" smd rect
			(at 59.173 -1.301)
			(size 0.35 2.5)
			(layers "B.Cu" "B.Mask")
			(net 117 "unconnected-(J1-Pad224)")
			(pinfunction "224")
			(pintype "passive+no_connect")
		)
		(pad "225" smd rect
			(at 59.423 -1.301)
			(size 0.35 2.5)
			(layers "F.Cu" "F.Mask")
			(net 118 "unconnected-(J1-Pad225)")
			(pinfunction "225")
			(pintype "passive+no_connect")
		)
		(pad "226" smd rect
			(at 59.673 -1.301)
			(size 0.35 2.5)
			(layers "B.Cu" "B.Mask")
			(net 119 "unconnected-(J1-Pad226)")
			(pinfunction "226")
			(pintype "passive+no_connect")
		)
		(pad "227" smd rect
			(at 59.923 -1.301)
			(size 0.35 2.5)
			(layers "F.Cu" "F.Mask")
			(net 120 "unconnected-(J1-Pad227)")
			(pinfunction "227")
			(pintype "passive+no_connect")
		)
		(pad "228" smd rect
			(at 60.173 -1.301)
			(size 0.35 2.5)
			(layers "B.Cu" "B.Mask")
			(net 121 "unconnected-(J1-Pad228)")
			(pinfunction "228")
			(pintype "passive+no_connect")
		)
		(pad "229" smd rect
			(at 60.423 -1.301)
			(size 0.35 2.5)
			(layers "F.Cu" "F.Mask")
			(net 122 "unconnected-(J1-Pad229)")
			(pinfunction "229")
			(pintype "passive+no_connect")
		)
		(pad "230" smd rect
			(at 60.673 -1.301)
			(size 0.35 2.5)
			(layers "B.Cu" "B.Mask")
			(net 123 "unconnected-(J1-Pad230)")
			(pinfunction "230")
			(pintype "passive+no_connect")
		)
		(pad "231" smd rect
			(at 60.923 -1.301)
			(size 0.35 2.5)
			(layers "F.Cu" "F.Mask")
			(net 124 "unconnected-(J1-Pad231)")
			(pinfunction "231")
			(pintype "passive+no_connect")
		)
		(pad "232" smd rect
			(at 61.173 -1.301)
			(size 0.35 2.5)
			(layers "B.Cu" "B.Mask")
			(net 125 "unconnected-(J1-Pad232)")
			(pinfunction "232")
			(pintype "passive+no_connect")
		)
		(pad "233" smd rect
			(at 61.423 -1.301)
			(size 0.35 2.5)
			(layers "F.Cu" "F.Mask")
			(net 126 "unconnected-(J1-Pad233)")
			(pinfunction "233")
			(pintype "passive+no_connect")
		)
		(pad "234" smd rect
			(at 61.673 -1.301)
			(size 0.35 2.5)
			(layers "B.Cu" "B.Mask")
			(net 127 "unconnected-(J1-Pad234)")
			(pinfunction "234")
			(pintype "passive+no_connect")
		)
		(pad "235" smd rect
			(at 61.923 -1.301)
			(size 0.35 2.5)
			(layers "F.Cu" "F.Mask")
			(net 128 "unconnected-(J1-Pad235)")
			(pinfunction "235")
			(pintype "passive+no_connect")
		)
		(pad "236" smd rect
			(at 62.173 -1.301)
			(size 0.35 2.5)
			(layers "B.Cu" "B.Mask")
			(net 129 "unconnected-(J1-Pad236)")
			(pinfunction "236")
			(pintype "passive+no_connect")
		)
		(pad "237" smd rect
			(at 62.423 -1.301)
			(size 0.35 2.5)
			(layers "F.Cu" "F.Mask")
			(net 130 "unconnected-(J1-Pad237)")
			(pinfunction "237")
			(pintype "passive+no_connect")
		)
		(pad "238" smd rect
			(at 62.673 -1.301)
			(size 0.35 2.5)
			(layers "B.Cu" "B.Mask")
			(net 131 "unconnected-(J1-Pad238)")
			(pinfunction "238")
			(pintype "passive+no_connect")
		)
		(pad "239" smd rect
			(at 62.923 -1.301)
			(size 0.35 2.5)
			(layers "F.Cu" "F.Mask")
			(net 132 "unconnected-(J1-Pad239)")
			(pinfunction "239")
			(pintype "passive+no_connect")
		)
		(pad "240" smd rect
			(at 63.173 -1.301)
			(size 0.35 2.5)
			(layers "B.Cu" "B.Mask")
			(net 133 "unconnected-(J1-Pad240)")
			(pinfunction "240")
			(pintype "passive+no_connect")
		)
		(pad "241" smd rect
			(at 63.423 -1.301)
			(size 0.35 2.5)
			(layers "F.Cu" "F.Mask")
			(net 134 "unconnected-(J1-Pad241)")
			(pinfunction "241")
			(pintype "passive+no_connect")
		)
		(pad "242" smd rect
			(at 63.673 -1.301)
			(size 0.35 2.5)
			(layers "B.Cu" "B.Mask")
			(net 135 "unconnected-(J1-Pad242)")
			(pinfunction "242")
			(pintype "passive+no_connect")
		)
		(pad "243" smd rect
			(at 63.923 -1.301)
			(size 0.35 2.5)
			(layers "F.Cu" "F.Mask")
			(net 136 "unconnected-(J1-Pad243)")
			(pinfunction "243")
			(pintype "passive+no_connect")
		)
		(pad "244" smd rect
			(at 64.174 -1.301)
			(size 0.35 2.5)
			(layers "B.Cu" "B.Mask")
			(net 137 "unconnected-(J1-Pad244)")
			(pinfunction "244")
			(pintype "passive+no_connect")
		)
		(pad "245" smd rect
			(at 64.424 -1.301)
			(size 0.35 2.5)
			(layers "F.Cu" "F.Mask")
			(net 138 "unconnected-(J1-Pad245)")
			(pinfunction "245")
			(pintype "passive+no_connect")
		)
		(pad "246" smd rect
			(at 64.674 -1.301)
			(size 0.35 2.5)
			(layers "B.Cu" "B.Mask")
			(net 189 "VDDQ")
			(pinfunction "246")
			(pintype "passive")
		)
		(pad "247" smd rect
			(at 64.924 -1.301)
			(size 0.35 2.5)
			(layers "F.Cu" "F.Mask")
			(net 139 "unconnected-(J1-Pad247)")
			(pinfunction "247")
			(pintype "passive+no_connect")
		)
		(pad "248" smd rect
			(at 65.174 -1.301)
			(size 0.35 2.5)
			(layers "B.Cu" "B.Mask")
			(net 189 "VDDQ")
			(pinfunction "248")
			(pintype "passive")
		)
		(pad "249" smd rect
			(at 65.424 -1.301)
			(size 0.35 2.5)
			(layers "F.Cu" "F.Mask")
			(net 140 "unconnected-(J1-Pad249)")
			(pinfunction "249")
			(pintype "passive+no_connect")
		)
		(pad "250" smd rect
			(at 65.674 -1.301)
			(size 0.35 2.5)
			(layers "B.Cu" "B.Mask")
			(net 189 "VDDQ")
			(pinfunction "250")
			(pintype "passive")
		)
		(pad "251" smd rect
			(at 65.924 -1.301)
			(size 0.35 2.5)
			(layers "F.Cu" "F.Mask")
			(net 141 "unconnected-(J1-Pad251)")
			(pinfunction "251")
			(pintype "passive+no_connect")
		)
		(pad "252" smd rect
			(at 66.174 -1.301)
			(size 0.35 2.5)
			(layers "B.Cu" "B.Mask")
			(net 142 "unconnected-(J1-Pad252)")
			(pinfunction "252")
			(pintype "passive+no_connect")
		)
		(pad "253" smd rect
			(at 66.424 -1.301)
			(size 0.35 2.5)
			(layers "F.Cu" "F.Mask")
			(net 143 "unconnected-(J1-Pad253)")
			(pinfunction "253")
			(pintype "passive+no_connect")
		)
		(pad "254" smd rect
			(at 66.674 -1.301)
			(size 0.35 2.5)
			(layers "B.Cu" "B.Mask")
			(net 144 "unconnected-(J1-Pad254)")
			(pinfunction "254")
			(pintype "passive+no_connect")
		)
		(pad "255" smd rect
			(at 66.924 -1.301)
			(size 0.35 2.5)
			(layers "F.Cu" "F.Mask")
			(net 145 "unconnected-(J1-Pad255)")
			(pinfunction "255")
			(pintype "passive+no_connect")
		)
		(pad "256" smd rect
			(at 67.174 -1.301)
			(size 0.35 2.5)
			(layers "B.Cu" "B.Mask")
			(net 146 "unconnected-(J1-Pad256)")
			(pinfunction "256")
			(pintype "passive+no_connect")
		)
		(pad "257" smd rect
			(at 67.424 -1.301)
			(size 0.35 2.5)
			(layers "F.Cu" "F.Mask")
			(net 147 "unconnected-(J1-Pad257)")
			(pinfunction "257")
			(pintype "passive+no_connect")
		)
		(pad "258" smd rect
			(at 67.674 -1.301)
			(size 0.35 2.5)
			(layers "B.Cu" "B.Mask")
			(net 148 "unconnected-(J1-Pad258)")
			(pinfunction "258")
			(pintype "passive+no_connect")
		)
		(pad "259" smd rect
			(at 67.924 -1.301)
			(size 0.35 2.5)
			(layers "F.Cu" "F.Mask")
			(net 149 "unconnected-(J1-Pad259)")
			(pinfunction "259")
			(pintype "passive+no_connect")
		)
		(pad "260" smd rect
			(at 68.174 -1.301)
			(size 0.35 2.5)
			(layers "B.Cu" "B.Mask")
			(net 150 "unconnected-(J1-Pad260)")
			(pinfunction "260")
			(pintype "passive+no_connect")
		)
	)
	(footprint "antmicro-footprints:R_0402_1005Metric"
		(layer "F.Cu")
		(at 158.375 87.5)
		(descr "Resistor SMD 0402")
		(tags "resistor SMD 0402")
		(property "Reference" "R2"
			(at 0.9 0.35 0)
			(layer "F.SilkS")
			(effects
				(font
					(size 0.7 0.7)
					(thickness 0.15)
				)
				(justify left bottom)
			)
		)
		(property "Value" "R_0R_0402"
			(at 0 1.4 0)
			(layer "F.Fab")
			(effects
				(font
					(size 0.7 0.7)
					(thickness 0.15)
				)
				(justify left bottom)
			)
		)
		(property "Description" "0R resistor in 0402 package with unspecified tolerance"
			(at 0 0 0)
			(layer "F.Fab")
			(hide yes)
			(effects
				(font
					(size 1.27 1.27)
					(thickness 0.15)
				)
			)
		)
		(property "Author" "Antmicro"
			(at 0 0 0)
			(layer "F.Fab")
			(hide yes)
			(effects
				(font
					(size 1 1)
					(thickness 0.15)
				)
			)
		)
		(property "Current" "1A"
			(at 0 0 0)
			(layer "F.Fab")
			(hide yes)
			(effects
				(font
					(size 1 1)
					(thickness 0.15)
				)
			)
		)
		(property "License" "Apache-2.0"
			(at 0 0 0)
			(layer "F.Fab")
			(hide yes)
			(effects
				(font
					(size 1 1)
					(thickness 0.15)
				)
			)
		)
		(property "MPN" "ERJ2GE0R00X"
			(at 0 0 0)
			(layer "F.Fab")
			(hide yes)
			(effects
				(font
					(size 1 1)
					(thickness 0.15)
				)
			)
		)
		(property "Manufacturer" "PANASONIC"
			(at 0 0 0)
			(layer "F.Fab")
			(hide yes)
			(effects
				(font
					(size 1 1)
					(thickness 0.15)
				)
			)
		)
		(property "Tolerance" ""
			(at 0 0 0)
			(layer "F.Fab")
			(hide yes)
			(effects
				(font
					(size 1 1)
					(thickness 0.15)
				)
			)
		)
		(property "Val" "0R"
			(at 0 0 0)
			(layer "F.Fab")
			(hide yes)
			(effects
				(font
					(size 1 1)
					(thickness 0.15)
				)
			)
		)
		(sheetname "LPDDR4")
		(sheetfile "lpddr4.kicad_sch")
		(attr smd)
		(fp_rect
			(start -0.93 -0.47)
			(end 0.93 0.47)
			(stroke
				(width 0.05)
				(type solid)
			)
			(fill no)
			(layer "F.CrtYd")
		)
		(fp_rect
			(start -0.5 -0.25)
			(end 0.5 0.25)
			(stroke
				(width 0.15)
				(type solid)
			)
			(fill no)
			(layer "F.Fab")
		)
		(pad "1" smd roundrect
			(at -0.485 0)
			(size 0.59 0.64)
			(layers "F.Cu" "F.Mask" "F.Paste")
			(roundrect_rratio 0.25)
			(net 158 "Net-(U1A-ODT_CA_A)")
			(pintype "passive")
		)
		(pad "2" smd roundrect
			(at 0.485 0)
			(size 0.59 0.64)
			(layers "F.Cu" "F.Mask" "F.Paste")
			(roundrect_rratio 0.25)
			(net 229 "ODT_CA_A")
			(pintype "passive")
		)
	)
	(footprint "antmicro-footprints:C_0201"
		(layer "F.Cu")
		(at 151.775 77.45 180)
		(descr "Capacitor SMD 0201")
		(tags "capacitor SMD 0201")
		(property "Reference" "C6"
			(at -0.7 0.4 0)
			(layer "F.SilkS")
			(effects
				(font
					(size 0.7 0.7)
					(thickness 0.15)
				)
				(justify right bottom)
			)
		)
		(property "Value" "C_100n_0201"
			(at 0 1.4 0)
			(layer "F.Fab")
			(effects
				(font
					(size 0.7 0.7)
					(thickness 0.15)
				)
				(justify right bottom)
			)
		)
		(property "Description" " "
			(at 0 0 180)
			(layer "F.Fab")
			(hide yes)
			(effects
				(font
					(size 1.27 1.27)
					(thickness 0.15)
				)
			)
		)
		(property "Author" "Antmicro"
			(at 303.55 154.9 0)
			(layer "F.Fab")
			(hide yes)
			(effects
				(font
					(size 1 1)
					(thickness 0.15)
				)
			)
		)
		(property "Dielectric" ""
			(at 303.55 154.9 0)
			(layer "F.Fab")
			(hide yes)
			(effects
				(font
					(size 1 1)
					(thickness 0.15)
				)
			)
		)
		(property "License" "Apache-2.0"
			(at 303.55 154.9 0)
			(layer "F.Fab")
			(hide yes)
			(effects
				(font
					(size 1 1)
					(thickness 0.15)
				)
			)
		)
		(property "MPN" "CC0201KRX6S5BB104"
			(at 303.55 154.9 0)
			(layer "F.Fab")
			(hide yes)
			(effects
				(font
					(size 1 1)
					(thickness 0.15)
				)
			)
		)
		(property "Manufacturer" "YAGEO"
			(at 303.55 154.9 0)
			(layer "F.Fab")
			(hide yes)
			(effects
				(font
					(size 1 1)
					(thickness 0.15)
				)
			)
		)
		(property "Val" "100n"
			(at 303.55 154.9 0)
			(layer "F.Fab")
			(hide yes)
			(effects
				(font
					(size 1 1)
					(thickness 0.15)
				)
			)
		)
		(property "Voltage" ""
			(at 303.55 154.9 0)
			(layer "F.Fab")
			(hide yes)
			(effects
				(font
					(size 1 1)
					(thickness 0.15)
				)
			)
		)
		(sheetname "LPDDR4")
		(sheetfile "lpddr4.kicad_sch")
		(attr smd)
		(fp_rect
			(start -0.72 -0.38)
			(end 0.72 0.38)
			(stroke
				(width 0.05)
				(type solid)
			)
			(fill no)
			(layer "F.CrtYd")
		)
		(fp_rect
			(start 0.3 0.15)
			(end -0.301 -0.149)
			(stroke
				(width 0.15)
				(type solid)
			)
			(fill no)
			(layer "F.Fab")
		)
		(pad "" smd roundrect
			(at -0.349 -0.002 180)
			(size 0.318 0.36)
			(layers "F.Paste")
			(roundrect_rratio 0.25)
		)
		(pad "" smd roundrect
			(at 0.341 -0.002 180)
			(size 0.318 0.36)
			(layers "F.Paste")
			(roundrect_rratio 0.25)
		)
		(pad "1" smd roundrect
			(at -0.321 -0.002 180)
			(size 0.46 0.4)
			(layers "F.Cu" "F.Mask")
			(roundrect_rratio 0.25)
			(net 36 "GND")
			(pintype "passive")
		)
		(pad "2" smd roundrect
			(at 0.32 -0.002 180)
			(size 0.46 0.4)
			(layers "F.Cu" "F.Mask")
			(roundrect_rratio 0.25)
			(net 188 "VDD2")
			(pintype "passive")
		)
	)
	(footprint "antmicro-footprints:C_0201"
		(layer "F.Cu")
		(at 155.855 88.2 -90)
		(descr "Capacitor SMD 0201")
		(tags "capacitor SMD 0201")
		(property "Reference" "C9"
			(at -1.05 -1.12 90)
			(layer "F.SilkS")
			(effects
				(font
					(size 0.7 0.7)
					(thickness 0.15)
				)
				(justify right bottom)
			)
		)
		(property "Value" "C_100n_0201"
			(at 0 1.4 90)
			(layer "F.Fab")
			(effects
				(font
					(size 0.7 0.7)
					(thickness 0.15)
				)
				(justify right bottom)
			)
		)
		(property "Description" " "
			(at 0 0 270)
			(layer "F.Fab")
			(hide yes)
			(effects
				(font
					(size 1.27 1.27)
					(thickness 0.15)
				)
			)
		)
		(property "Author" "Antmicro"
			(at 67.655 244.055 0)
			(layer "F.Fab")
			(hide yes)
			(effects
				(font
					(size 1 1)
					(thickness 0.15)
				)
			)
		)
		(property "Dielectric" ""
			(at 67.655 244.055 0)
			(layer "F.Fab")
			(hide yes)
			(effects
				(font
					(size 1 1)
					(thickness 0.15)
				)
			)
		)
		(property "License" "Apache-2.0"
			(at 67.655 244.055 0)
			(layer "F.Fab")
			(hide yes)
			(effects
				(font
					(size 1 1)
					(thickness 0.15)
				)
			)
		)
		(property "MPN" "CC0201KRX6S5BB104"
			(at 67.655 244.055 0)
			(layer "F.Fab")
			(hide yes)
			(effects
				(font
					(size 1 1)
					(thickness 0.15)
				)
			)
		)
		(property "Manufacturer" "YAGEO"
			(at 67.655 244.055 0)
			(layer "F.Fab")
			(hide yes)
			(effects
				(font
					(size 1 1)
					(thickness 0.15)
				)
			)
		)
		(property "Val" "100n"
			(at 67.655 244.055 0)
			(layer "F.Fab")
			(hide yes)
			(effects
				(font
					(size 1 1)
					(thickness 0.15)
				)
			)
		)
		(property "Voltage" ""
			(at 67.655 244.055 0)
			(layer "F.Fab")
			(hide yes)
			(effects
				(font
					(size 1 1)
					(thickness 0.15)
				)
			)
		)
		(sheetname "LPDDR4")
		(sheetfile "lpddr4.kicad_sch")
		(attr smd)
		(fp_rect
			(start -0.72 -0.38)
			(end 0.72 0.38)
			(stroke
				(width 0.05)
				(type solid)
			)
			(fill no)
			(layer "F.CrtYd")
		)
		(fp_rect
			(start 0.3 0.15)
			(end -0.301 -0.149)
			(stroke
				(width 0.15)
				(type solid)
			)
			(fill no)
			(layer "F.Fab")
		)
		(pad "" smd roundrect
			(at -0.349 -0.002 270)
			(size 0.318 0.36)
			(layers "F.Paste")
			(roundrect_rratio 0.25)
		)
		(pad "" smd roundrect
			(at 0.341 -0.002 270)
			(size 0.318 0.36)
			(layers "F.Paste")
			(roundrect_rratio 0.25)
		)
		(pad "1" smd roundrect
			(at -0.321 -0.002 270)
			(size 0.46 0.4)
			(layers "F.Cu" "F.Mask")
			(roundrect_rratio 0.25)
			(net 36 "GND")
			(pintype "passive")
		)
		(pad "2" smd roundrect
			(at 0.32 -0.002 270)
			(size 0.46 0.4)
			(layers "F.Cu" "F.Mask")
			(roundrect_rratio 0.25)
			(net 188 "VDD2")
			(pintype "passive")
		)
	)
	(footprint "antmicro-footprints:C_0201"
		(layer "F.Cu")
		(at 155.855 81.2 -90)
		(descr "Capacitor SMD 0201")
		(tags "capacitor SMD 0201")
		(property "Reference" "C11"
			(at -1.45 -1.22 90)
			(layer "F.SilkS")
			(effects
				(font
					(size 0.7 0.7)
					(thickness 0.15)
				)
				(justify right bottom)
			)
		)
		(property "Value" "C_100n_0201"
			(at 0 1.4 90)
			(layer "F.Fab")
			(effects
				(font
					(size 0.7 0.7)
					(thickness 0.15)
				)
				(justify right bottom)
			)
		)
		(property "Description" " "
			(at 0 0 270)
			(layer "F.Fab")
			(hide yes)
			(effects
				(font
					(size 1.27 1.27)
					(thickness 0.15)
				)
			)
		)
		(property "Author" "Antmicro"
			(at 74.655 237.055 0)
			(layer "F.Fab")
			(hide yes)
			(effects
				(font
					(size 1 1)
					(thickness 0.15)
				)
			)
		)
		(property "Dielectric" ""
			(at 74.655 237.055 0)
			(layer "F.Fab")
			(hide yes)
			(effects
				(font
					(size 1 1)
					(thickness 0.15)
				)
			)
		)
		(property "License" "Apache-2.0"
			(at 74.655 237.055 0)
			(layer "F.Fab")
			(hide yes)
			(effects
				(font
					(size 1 1)
					(thickness 0.15)
				)
			)
		)
		(property "MPN" "CC0201KRX6S5BB104"
			(at 74.655 237.055 0)
			(layer "F.Fab")
			(hide yes)
			(effects
				(font
					(size 1 1)
					(thickness 0.15)
				)
			)
		)
		(property "Manufacturer" "YAGEO"
			(at 74.655 237.055 0)
			(layer "F.Fab")
			(hide yes)
			(effects
				(font
					(size 1 1)
					(thickness 0.15)
				)
			)
		)
		(property "Val" "100n"
			(at 74.655 237.055 0)
			(layer "F.Fab")
			(hide yes)
			(effects
				(font
					(size 1 1)
					(thickness 0.15)
				)
			)
		)
		(property "Voltage" ""
			(at 74.655 237.055 0)
			(layer "F.Fab")
			(hide yes)
			(effects
				(font
					(size 1 1)
					(thickness 0.15)
				)
			)
		)
		(sheetname "LPDDR4")
		(sheetfile "lpddr4.kicad_sch")
		(attr smd)
		(fp_rect
			(start -0.72 -0.38)
			(end 0.72 0.38)
			(stroke
				(width 0.05)
				(type solid)
			)
			(fill no)
			(layer "F.CrtYd")
		)
		(fp_rect
			(start 0.3 0.15)
			(end -0.301 -0.149)
			(stroke
				(width 0.15)
				(type solid)
			)
			(fill no)
			(layer "F.Fab")
		)
		(pad "" smd roundrect
			(at -0.349 -0.002 270)
			(size 0.318 0.36)
			(layers "F.Paste")
			(roundrect_rratio 0.25)
		)
		(pad "" smd roundrect
			(at 0.341 -0.002 270)
			(size 0.318 0.36)
			(layers "F.Paste")
			(roundrect_rratio 0.25)
		)
		(pad "1" smd roundrect
			(at -0.321 -0.002 270)
			(size 0.46 0.4)
			(layers "F.Cu" "F.Mask")
			(roundrect_rratio 0.25)
			(net 36 "GND")
			(pintype "passive")
		)
		(pad "2" smd roundrect
			(at 0.32 -0.002 270)
			(size 0.46 0.4)
			(layers "F.Cu" "F.Mask")
			(roundrect_rratio 0.25)
			(net 189 "VDDQ")
			(pintype "passive")
		)
	)
	(footprint "antmicro-footprints:C_0201"
		(layer "F.Cu")
		(at 147.251 94.861)
		(descr "Capacitor SMD 0201")
		(tags "capacitor SMD 0201")
		(property "Reference" "C3"
			(at -0.776 1.089 0)
			(layer "F.SilkS")
			(effects
				(font
					(size 0.7 0.7)
					(thickness 0.15)
				)
				(justify left bottom)
			)
		)
		(property "Value" "C_100n_0201"
			(at 0 1.4 0)
			(layer "F.Fab")
			(effects
				(font
					(size 0.7 0.7)
					(thickness 0.15)
				)
				(justify left bottom)
			)
		)
		(property "Description" " "
			(at 0 0 0)
			(layer "F.Fab")
			(hide yes)
			(effects
				(font
					(size 1.27 1.27)
					(thickness 0.15)
				)
			)
		)
		(property "Author" "Antmicro"
			(at 0 0 0)
			(layer "F.Fab")
			(hide yes)
			(effects
				(font
					(size 1 1)
					(thickness 0.15)
				)
			)
		)
		(property "Dielectric" ""
			(at 0 0 0)
			(layer "F.Fab")
			(hide yes)
			(effects
				(font
					(size 1 1)
					(thickness 0.15)
				)
			)
		)
		(property "License" "Apache-2.0"
			(at 0 0 0)
			(layer "F.Fab")
			(hide yes)
			(effects
				(font
					(size 1 1)
					(thickness 0.15)
				)
			)
		)
		(property "MPN" "CC0201KRX6S5BB104"
			(at 0 0 0)
			(layer "F.Fab")
			(hide yes)
			(effects
				(font
					(size 1 1)
					(thickness 0.15)
				)
			)
		)
		(property "Manufacturer" "YAGEO"
			(at 0 0 0)
			(layer "F.Fab")
			(hide yes)
			(effects
				(font
					(size 1 1)
					(thickness 0.15)
				)
			)
		)
		(property "Val" "100n"
			(at 0 0 0)
			(layer "F.Fab")
			(hide yes)
			(effects
				(font
					(size 1 1)
					(thickness 0.15)
				)
			)
		)
		(property "Voltage" ""
			(at 0 0 0)
			(layer "F.Fab")
			(hide yes)
			(effects
				(font
					(size 1 1)
					(thickness 0.15)
				)
			)
		)
		(sheetname "LPDDR4")
		(sheetfile "lpddr4.kicad_sch")
		(attr smd)
		(fp_rect
			(start -0.72 -0.38)
			(end 0.72 0.38)
			(stroke
				(width 0.05)
				(type solid)
			)
			(fill no)
			(layer "F.CrtYd")
		)
		(fp_rect
			(start 0.3 0.15)
			(end -0.301 -0.149)
			(stroke
				(width 0.15)
				(type solid)
			)
			(fill no)
			(layer "F.Fab")
		)
		(pad "" smd roundrect
			(at -0.349 -0.002)
			(size 0.318 0.36)
			(layers "F.Paste")
			(roundrect_rratio 0.25)
		)
		(pad "" smd roundrect
			(at 0.341 -0.002)
			(size 0.318 0.36)
			(layers "F.Paste")
			(roundrect_rratio 0.25)
		)
		(pad "1" smd roundrect
			(at -0.321 -0.002)
			(size 0.46 0.4)
			(layers "F.Cu" "F.Mask")
			(roundrect_rratio 0.25)
			(net 36 "GND")
			(pintype "passive")
		)
		(pad "2" smd roundrect
			(at 0.32 -0.002)
			(size 0.46 0.4)
			(layers "F.Cu" "F.Mask")
			(roundrect_rratio 0.25)
			(net 188 "VDD2")
			(pintype "passive")
		)
	)
	(footprint "antmicro-footprints:C_0201"
		(layer "F.Cu")
		(at 155.855 84.9 90)
		(descr "Capacitor SMD 0201")
		(tags "capacitor SMD 0201")
		(property "Reference" "C18"
			(at -1.35 1.32 90)
			(layer "F.SilkS")
			(effects
				(font
					(size 0.7 0.7)
					(thickness 0.15)
				)
				(justify left bottom)
			)
		)
		(property "Value" "C_100n_0201"
			(at 0 1.4 90)
			(layer "F.Fab")
			(effects
				(font
					(size 0.7 0.7)
					(thickness 0.15)
				)
				(justify left bottom)
			)
		)
		(property "Description" " "
			(at 0 0 90)
			(layer "F.Fab")
			(hide yes)
			(effects
				(font
					(size 1.27 1.27)
					(thickness 0.15)
				)
			)
		)
		(property "Author" "Antmicro"
			(at 240.755 -70.955 0)
			(layer "F.Fab")
			(hide yes)
			(effects
				(font
					(size 1 1)
					(thickness 0.15)
				)
			)
		)
		(property "Dielectric" ""
			(at 240.755 -70.955 0)
			(layer "F.Fab")
			(hide yes)
			(effects
				(font
					(size 1 1)
					(thickness 0.15)
				)
			)
		)
		(property "License" "Apache-2.0"
			(at 240.755 -70.955 0)
			(layer "F.Fab")
			(hide yes)
			(effects
				(font
					(size 1 1)
					(thickness 0.15)
				)
			)
		)
		(property "MPN" "CC0201KRX6S5BB104"
			(at 240.755 -70.955 0)
			(layer "F.Fab")
			(hide yes)
			(effects
				(font
					(size 1 1)
					(thickness 0.15)
				)
			)
		)
		(property "Manufacturer" "YAGEO"
			(at 240.755 -70.955 0)
			(layer "F.Fab")
			(hide yes)
			(effects
				(font
					(size 1 1)
					(thickness 0.15)
				)
			)
		)
		(property "Val" "100n"
			(at 240.755 -70.955 0)
			(layer "F.Fab")
			(hide yes)
			(effects
				(font
					(size 1 1)
					(thickness 0.15)
				)
			)
		)
		(property "Voltage" ""
			(at 240.755 -70.955 0)
			(layer "F.Fab")
			(hide yes)
			(effects
				(font
					(size 1 1)
					(thickness 0.15)
				)
			)
		)
		(sheetname "LPDDR4")
		(sheetfile "lpddr4.kicad_sch")
		(attr smd)
		(fp_rect
			(start -0.72 -0.38)
			(end 0.72 0.38)
			(stroke
				(width 0.05)
				(type solid)
			)
			(fill no)
			(layer "F.CrtYd")
		)
		(fp_rect
			(start 0.3 0.15)
			(end -0.301 -0.149)
			(stroke
				(width 0.15)
				(type solid)
			)
			(fill no)
			(layer "F.Fab")
		)
		(pad "" smd roundrect
			(at -0.349 -0.002 90)
			(size 0.318 0.36)
			(layers "F.Paste")
			(roundrect_rratio 0.25)
		)
		(pad "" smd roundrect
			(at 0.341 -0.002 90)
			(size 0.318 0.36)
			(layers "F.Paste")
			(roundrect_rratio 0.25)
		)
		(pad "1" smd roundrect
			(at -0.321 -0.002 90)
			(size 0.46 0.4)
			(layers "F.Cu" "F.Mask")
			(roundrect_rratio 0.25)
			(net 36 "GND")
			(pintype "passive")
		)
		(pad "2" smd roundrect
			(at 0.32 -0.002 90)
			(size 0.46 0.4)
			(layers "F.Cu" "F.Mask")
			(roundrect_rratio 0.25)
			(net 188 "VDD2")
			(pintype "passive")
		)
	)
	(footprint "antmicro-footprints:C_0201"
		(layer "F.Cu")
		(at 146.925 77.45)
		(descr "Capacitor SMD 0201")
		(tags "capacitor SMD 0201")
		(property "Reference" "C22"
			(at -1.05 -0.4 0)
			(layer "F.SilkS")
			(effects
				(font
					(size 0.7 0.7)
					(thickness 0.15)
				)
				(justify left bottom)
			)
		)
		(property "Value" "C_100n_0201"
			(at 0 1.4 0)
			(layer "F.Fab")
			(effects
				(font
					(size 0.7 0.7)
					(thickness 0.15)
				)
				(justify left bottom)
			)
		)
		(property "Description" " "
			(at 0 0 0)
			(layer "F.Fab")
			(hide yes)
			(effects
				(font
					(size 1.27 1.27)
					(thickness 0.15)
				)
			)
		)
		(property "Author" "Antmicro"
			(at 0 0 0)
			(layer "F.Fab")
			(hide yes)
			(effects
				(font
					(size 1 1)
					(thickness 0.15)
				)
			)
		)
		(property "Dielectric" ""
			(at 0 0 0)
			(layer "F.Fab")
			(hide yes)
			(effects
				(font
					(size 1 1)
					(thickness 0.15)
				)
			)
		)
		(property "License" "Apache-2.0"
			(at 0 0 0)
			(layer "F.Fab")
			(hide yes)
			(effects
				(font
					(size 1 1)
					(thickness 0.15)
				)
			)
		)
		(property "MPN" "CC0201KRX6S5BB104"
			(at 0 0 0)
			(layer "F.Fab")
			(hide yes)
			(effects
				(font
					(size 1 1)
					(thickness 0.15)
				)
			)
		)
		(property "Manufacturer" "YAGEO"
			(at 0 0 0)
			(layer "F.Fab")
			(hide yes)
			(effects
				(font
					(size 1 1)
					(thickness 0.15)
				)
			)
		)
		(property "Val" "100n"
			(at 0 0 0)
			(layer "F.Fab")
			(hide yes)
			(effects
				(font
					(size 1 1)
					(thickness 0.15)
				)
			)
		)
		(property "Voltage" ""
			(at 0 0 0)
			(layer "F.Fab")
			(hide yes)
			(effects
				(font
					(size 1 1)
					(thickness 0.15)
				)
			)
		)
		(sheetname "LPDDR4")
		(sheetfile "lpddr4.kicad_sch")
		(attr smd)
		(fp_rect
			(start -0.72 -0.38)
			(end 0.72 0.38)
			(stroke
				(width 0.05)
				(type solid)
			)
			(fill no)
			(layer "F.CrtYd")
		)
		(fp_rect
			(start 0.3 0.15)
			(end -0.301 -0.149)
			(stroke
				(width 0.15)
				(type solid)
			)
			(fill no)
			(layer "F.Fab")
		)
		(pad "" smd roundrect
			(at -0.349 -0.002)
			(size 0.318 0.36)
			(layers "F.Paste")
			(roundrect_rratio 0.25)
		)
		(pad "" smd roundrect
			(at 0.341 -0.002)
			(size 0.318 0.36)
			(layers "F.Paste")
			(roundrect_rratio 0.25)
		)
		(pad "1" smd roundrect
			(at -0.321 -0.002)
			(size 0.46 0.4)
			(layers "F.Cu" "F.Mask")
			(roundrect_rratio 0.25)
			(net 36 "GND")
			(pintype "passive")
		)
		(pad "2" smd roundrect
			(at 0.32 -0.002)
			(size 0.46 0.4)
			(layers "F.Cu" "F.Mask")
			(roundrect_rratio 0.25)
			(net 188 "VDD2")
			(pintype "passive")
		)
	)
	(footprint "antmicro-footprints:C_0201"
		(layer "F.Cu")
		(at 142.725 91.05 90)
		(descr "Capacitor SMD 0201")
		(tags "capacitor SMD 0201")
		(property "Reference" "C14"
			(at -2.9 0.25 90)
			(layer "F.SilkS")
			(effects
				(font
					(size 0.7 0.7)
					(thickness 0.15)
				)
				(justify left bottom)
			)
		)
		(property "Value" "C_100n_0201"
			(at 0 1.4 90)
			(layer "F.Fab")
			(effects
				(font
					(size 0.7 0.7)
					(thickness 0.15)
				)
				(justify left bottom)
			)
		)
		(property "Description" " "
			(at 0 0 90)
			(layer "F.Fab")
			(hide yes)
			(effects
				(font
					(size 1.27 1.27)
					(thickness 0.15)
				)
			)
		)
		(property "Author" "Antmicro"
			(at 233.775 -51.675 0)
			(layer "F.Fab")
			(hide yes)
			(effects
				(font
					(size 1 1)
					(thickness 0.15)
				)
			)
		)
		(property "Dielectric" ""
			(at 233.775 -51.675 0)
			(layer "F.Fab")
			(hide yes)
			(effects
				(font
					(size 1 1)
					(thickness 0.15)
				)
			)
		)
		(property "License" "Apache-2.0"
			(at 233.775 -51.675 0)
			(layer "F.Fab")
			(hide yes)
			(effects
				(font
					(size 1 1)
					(thickness 0.15)
				)
			)
		)
		(property "MPN" "CC0201KRX6S5BB104"
			(at 233.775 -51.675 0)
			(layer "F.Fab")
			(hide yes)
			(effects
				(font
					(size 1 1)
					(thickness 0.15)
				)
			)
		)
		(property "Manufacturer" "YAGEO"
			(at 233.775 -51.675 0)
			(layer "F.Fab")
			(hide yes)
			(effects
				(font
					(size 1 1)
					(thickness 0.15)
				)
			)
		)
		(property "Val" "100n"
			(at 233.775 -51.675 0)
			(layer "F.Fab")
			(hide yes)
			(effects
				(font
					(size 1 1)
					(thickness 0.15)
				)
			)
		)
		(property "Voltage" ""
			(at 233.775 -51.675 0)
			(layer "F.Fab")
			(hide yes)
			(effects
				(font
					(size 1 1)
					(thickness 0.15)
				)
			)
		)
		(sheetname "LPDDR4")
		(sheetfile "lpddr4.kicad_sch")
		(attr smd)
		(fp_rect
			(start -0.72 -0.38)
			(end 0.72 0.38)
			(stroke
				(width 0.05)
				(type solid)
			)
			(fill no)
			(layer "F.CrtYd")
		)
		(fp_rect
			(start 0.3 0.15)
			(end -0.301 -0.149)
			(stroke
				(width 0.15)
				(type solid)
			)
			(fill no)
			(layer "F.Fab")
		)
		(pad "" smd roundrect
			(at -0.349 -0.002 90)
			(size 0.318 0.36)
			(layers "F.Paste")
			(roundrect_rratio 0.25)
		)
		(pad "" smd roundrect
			(at 0.341 -0.002 90)
			(size 0.318 0.36)
			(layers "F.Paste")
			(roundrect_rratio 0.25)
		)
		(pad "1" smd roundrect
			(at -0.321 -0.002 90)
			(size 0.46 0.4)
			(layers "F.Cu" "F.Mask")
			(roundrect_rratio 0.25)
			(net 36 "GND")
			(pintype "passive")
		)
		(pad "2" smd roundrect
			(at 0.32 -0.002 90)
			(size 0.46 0.4)
			(layers "F.Cu" "F.Mask")
			(roundrect_rratio 0.25)
			(net 189 "VDDQ")
			(pintype "passive")
		)
	)
	(footprint "antmicro-footprints:C_0201"
		(layer "F.Cu")
		(at 142.925 87.6 -90)
		(descr "Capacitor SMD 0201")
		(tags "capacitor SMD 0201")
		(property "Reference" "C20"
			(at -1.25 0.55 90)
			(layer "F.SilkS")
			(effects
				(font
					(size 0.7 0.7)
					(thickness 0.15)
				)
				(justify right bottom)
			)
		)
		(property "Value" "C_100n_0201"
			(at 0 1.4 90)
			(layer "F.Fab")
			(effects
				(font
					(size 0.7 0.7)
					(thickness 0.15)
				)
				(justify right bottom)
			)
		)
		(property "Description" " "
			(at 0 0 270)
			(layer "F.Fab")
			(hide yes)
			(effects
				(font
					(size 1.27 1.27)
					(thickness 0.15)
				)
			)
		)
		(property "Author" "Antmicro"
			(at 55.325 230.525 0)
			(layer "F.Fab")
			(hide yes)
			(effects
				(font
					(size 1 1)
					(thickness 0.15)
				)
			)
		)
		(property "Dielectric" ""
			(at 55.325 230.525 0)
			(layer "F.Fab")
			(hide yes)
			(effects
				(font
					(size 1 1)
					(thickness 0.15)
				)
			)
		)
		(property "License" "Apache-2.0"
			(at 55.325 230.525 0)
			(layer "F.Fab")
			(hide yes)
			(effects
				(font
					(size 1 1)
					(thickness 0.15)
				)
			)
		)
		(property "MPN" "CC0201KRX6S5BB104"
			(at 55.325 230.525 0)
			(layer "F.Fab")
			(hide yes)
			(effects
				(font
					(size 1 1)
					(thickness 0.15)
				)
			)
		)
		(property "Manufacturer" "YAGEO"
			(at 55.325 230.525 0)
			(layer "F.Fab")
			(hide yes)
			(effects
				(font
					(size 1 1)
					(thickness 0.15)
				)
			)
		)
		(property "Val" "100n"
			(at 55.325 230.525 0)
			(layer "F.Fab")
			(hide yes)
			(effects
				(font
					(size 1 1)
					(thickness 0.15)
				)
			)
		)
		(property "Voltage" ""
			(at 55.325 230.525 0)
			(layer "F.Fab")
			(hide yes)
			(effects
				(font
					(size 1 1)
					(thickness 0.15)
				)
			)
		)
		(sheetname "LPDDR4")
		(sheetfile "lpddr4.kicad_sch")
		(attr smd)
		(fp_rect
			(start -0.72 -0.38)
			(end 0.72 0.38)
			(stroke
				(width 0.05)
				(type solid)
			)
			(fill no)
			(layer "F.CrtYd")
		)
		(fp_rect
			(start 0.3 0.15)
			(end -0.301 -0.149)
			(stroke
				(width 0.15)
				(type solid)
			)
			(fill no)
			(layer "F.Fab")
		)
		(pad "" smd roundrect
			(at -0.349 -0.002 270)
			(size 0.318 0.36)
			(layers "F.Paste")
			(roundrect_rratio 0.25)
		)
		(pad "" smd roundrect
			(at 0.341 -0.002 270)
			(size 0.318 0.36)
			(layers "F.Paste")
			(roundrect_rratio 0.25)
		)
		(pad "1" smd roundrect
			(at -0.321 -0.002 270)
			(size 0.46 0.4)
			(layers "F.Cu" "F.Mask")
			(roundrect_rratio 0.25)
			(net 36 "GND")
			(pintype "passive")
		)
		(pad "2" smd roundrect
			(at 0.32 -0.002 270)
			(size 0.46 0.4)
			(layers "F.Cu" "F.Mask")
			(roundrect_rratio 0.25)
			(net 188 "VDD2")
			(pintype "passive")
		)
	)
	(footprint "antmicro-footprints:C_0201"
		(layer "F.Cu")
		(at 155.855 91.7 90)
		(descr "Capacitor SMD 0201")
		(tags "capacitor SMD 0201")
		(property "Reference" "C21"
			(at -1.05 1.22 90)
			(layer "F.SilkS")
			(effects
				(font
					(size 0.7 0.7)
					(thickness 0.15)
				)
				(justify left bottom)
			)
		)
		(property "Value" "C_100n_0201"
			(at 0 1.4 90)
			(layer "F.Fab")
			(effects
				(font
					(size 0.7 0.7)
					(thickness 0.15)
				)
				(justify left bottom)
			)
		)
		(property "Description" " "
			(at 0 0 90)
			(layer "F.Fab")
			(hide yes)
			(effects
				(font
					(size 1.27 1.27)
					(thickness 0.15)
				)
			)
		)
		(property "Author" "Antmicro"
			(at 247.555 -64.155 0)
			(layer "F.Fab")
			(hide yes)
			(effects
				(font
					(size 1 1)
					(thickness 0.15)
				)
			)
		)
		(property "Dielectric" ""
			(at 247.555 -64.155 0)
			(layer "F.Fab")
			(hide yes)
			(effects
				(font
					(size 1 1)
					(thickness 0.15)
				)
			)
		)
		(property "License" "Apache-2.0"
			(at 247.555 -64.155 0)
			(layer "F.Fab")
			(hide yes)
			(effects
				(font
					(size 1 1)
					(thickness 0.15)
				)
			)
		)
		(property "MPN" "CC0201KRX6S5BB104"
			(at 247.555 -64.155 0)
			(layer "F.Fab")
			(hide yes)
			(effects
				(font
					(size 1 1)
					(thickness 0.15)
				)
			)
		)
		(property "Manufacturer" "YAGEO"
			(at 247.555 -64.155 0)
			(layer "F.Fab")
			(hide yes)
			(effects
				(font
					(size 1 1)
					(thickness 0.15)
				)
			)
		)
		(property "Val" "100n"
			(at 247.555 -64.155 0)
			(layer "F.Fab")
			(hide yes)
			(effects
				(font
					(size 1 1)
					(thickness 0.15)
				)
			)
		)
		(property "Voltage" ""
			(at 247.555 -64.155 0)
			(layer "F.Fab")
			(hide yes)
			(effects
				(font
					(size 1 1)
					(thickness 0.15)
				)
			)
		)
		(sheetname "LPDDR4")
		(sheetfile "lpddr4.kicad_sch")
		(attr smd)
		(fp_rect
			(start -0.72 -0.38)
			(end 0.72 0.38)
			(stroke
				(width 0.05)
				(type solid)
			)
			(fill no)
			(layer "F.CrtYd")
		)
		(fp_rect
			(start 0.3 0.15)
			(end -0.301 -0.149)
			(stroke
				(width 0.15)
				(type solid)
			)
			(fill no)
			(layer "F.Fab")
		)
		(pad "" smd roundrect
			(at -0.349 -0.002 90)
			(size 0.318 0.36)
			(layers "F.Paste")
			(roundrect_rratio 0.25)
		)
		(pad "" smd roundrect
			(at 0.341 -0.002 90)
			(size 0.318 0.36)
			(layers "F.Paste")
			(roundrect_rratio 0.25)
		)
		(pad "1" smd roundrect
			(at -0.321 -0.002 90)
			(size 0.46 0.4)
			(layers "F.Cu" "F.Mask")
			(roundrect_rratio 0.25)
			(net 36 "GND")
			(pintype "passive")
		)
		(pad "2" smd roundrect
			(at 0.32 -0.002 90)
			(size 0.46 0.4)
			(layers "F.Cu" "F.Mask")
			(roundrect_rratio 0.25)
			(net 189 "VDDQ")
			(pintype "passive")
		)
	)
	(footprint "antmicro-footprints:C_0201"
		(layer "F.Cu")
		(at 155.855 82.7 -90)
		(descr "Capacitor SMD 0201")
		(tags "capacitor SMD 0201")
		(property "Reference" "C25"
			(at -0.75 -1.22 90)
			(layer "F.SilkS")
			(effects
				(font
					(size 0.7 0.7)
					(thickness 0.15)
				)
				(justify right bottom)
			)
		)
		(property "Value" "C_100n_0201"
			(at 0 1.4 90)
			(layer "F.Fab")
			(effects
				(font
					(size 0.7 0.7)
					(thickness 0.15)
				)
				(justify right bottom)
			)
		)
		(property "Description" " "
			(at 0 0 270)
			(layer "F.Fab")
			(hide yes)
			(effects
				(font
					(size 1.27 1.27)
					(thickness 0.15)
				)
			)
		)
		(property "Author" "Antmicro"
			(at 73.155 238.555 0)
			(layer "F.Fab")
			(hide yes)
			(effects
				(font
					(size 1 1)
					(thickness 0.15)
				)
			)
		)
		(property "Dielectric" ""
			(at 73.155 238.555 0)
			(layer "F.Fab")
			(hide yes)
			(effects
				(font
					(size 1 1)
					(thickness 0.15)
				)
			)
		)
		(property "License" "Apache-2.0"
			(at 73.155 238.555 0)
			(layer "F.Fab")
			(hide yes)
			(effects
				(font
					(size 1 1)
					(thickness 0.15)
				)
			)
		)
		(property "MPN" "CC0201KRX6S5BB104"
			(at 73.155 238.555 0)
			(layer "F.Fab")
			(hide yes)
			(effects
				(font
					(size 1 1)
					(thickness 0.15)
				)
			)
		)
		(property "Manufacturer" "YAGEO"
			(at 73.155 238.555 0)
			(layer "F.Fab")
			(hide yes)
			(effects
				(font
					(size 1 1)
					(thickness 0.15)
				)
			)
		)
		(property "Val" "100n"
			(at 73.155 238.555 0)
			(layer "F.Fab")
			(hide yes)
			(effects
				(font
					(size 1 1)
					(thickness 0.15)
				)
			)
		)
		(property "Voltage" ""
			(at 73.155 238.555 0)
			(layer "F.Fab")
			(hide yes)
			(effects
				(font
					(size 1 1)
					(thickness 0.15)
				)
			)
		)
		(sheetname "LPDDR4")
		(sheetfile "lpddr4.kicad_sch")
		(attr smd)
		(fp_rect
			(start -0.72 -0.38)
			(end 0.72 0.38)
			(stroke
				(width 0.05)
				(type solid)
			)
			(fill no)
			(layer "F.CrtYd")
		)
		(fp_rect
			(start 0.3 0.15)
			(end -0.301 -0.149)
			(stroke
				(width 0.15)
				(type solid)
			)
			(fill no)
			(layer "F.Fab")
		)
		(pad "" smd roundrect
			(at -0.349 -0.002 270)
			(size 0.318 0.36)
			(layers "F.Paste")
			(roundrect_rratio 0.25)
		)
		(pad "" smd roundrect
			(at 0.341 -0.002 270)
			(size 0.318 0.36)
			(layers "F.Paste")
			(roundrect_rratio 0.25)
		)
		(pad "1" smd roundrect
			(at -0.321 -0.002 270)
			(size 0.46 0.4)
			(layers "F.Cu" "F.Mask")
			(roundrect_rratio 0.25)
			(net 36 "GND")
			(pintype "passive")
		)
		(pad "2" smd roundrect
			(at 0.32 -0.002 270)
			(size 0.46 0.4)
			(layers "F.Cu" "F.Mask")
			(roundrect_rratio 0.25)
			(net 187 "VDD1")
			(pintype "passive")
		)
	)
	(footprint "antmicro-footprints:C_0201"
		(layer "F.Cu")
		(at 152.167 94.891 180)
		(descr "Capacitor SMD 0201")
		(tags "capacitor SMD 0201")
		(property "Reference" "C26"
			(at -1.008 -1.259 0)
			(layer "F.SilkS")
			(effects
				(font
					(size 0.7 0.7)
					(thickness 0.15)
				)
				(justify right bottom)
			)
		)
		(property "Value" "C_100n_0201"
			(at 0 1.4 0)
			(layer "F.Fab")
			(effects
				(font
					(size 0.7 0.7)
					(thickness 0.15)
				)
				(justify right bottom)
			)
		)
		(property "Description" " "
			(at 0 0 180)
			(layer "F.Fab")
			(hide yes)
			(effects
				(font
					(size 1.27 1.27)
					(thickness 0.15)
				)
			)
		)
		(property "Author" "Antmicro"
			(at 304.334 189.782 0)
			(layer "F.Fab")
			(hide yes)
			(effects
				(font
					(size 1 1)
					(thickness 0.15)
				)
			)
		)
		(property "Dielectric" ""
			(at 304.334 189.782 0)
			(layer "F.Fab")
			(hide yes)
			(effects
				(font
					(size 1 1)
					(thickness 0.15)
				)
			)
		)
		(property "License" "Apache-2.0"
			(at 304.334 189.782 0)
			(layer "F.Fab")
			(hide yes)
			(effects
				(font
					(size 1 1)
					(thickness 0.15)
				)
			)
		)
		(property "MPN" "CC0201KRX6S5BB104"
			(at 304.334 189.782 0)
			(layer "F.Fab")
			(hide yes)
			(effects
				(font
					(size 1 1)
					(thickness 0.15)
				)
			)
		)
		(property "Manufacturer" "YAGEO"
			(at 304.334 189.782 0)
			(layer "F.Fab")
			(hide yes)
			(effects
				(font
					(size 1 1)
					(thickness 0.15)
				)
			)
		)
		(property "Val" "100n"
			(at 304.334 189.782 0)
			(layer "F.Fab")
			(hide yes)
			(effects
				(font
					(size 1 1)
					(thickness 0.15)
				)
			)
		)
		(property "Voltage" ""
			(at 304.334 189.782 0)
			(layer "F.Fab")
			(hide yes)
			(effects
				(font
					(size 1 1)
					(thickness 0.15)
				)
			)
		)
		(sheetname "LPDDR4")
		(sheetfile "lpddr4.kicad_sch")
		(attr smd)
		(fp_rect
			(start -0.72 -0.38)
			(end 0.72 0.38)
			(stroke
				(width 0.05)
				(type solid)
			)
			(fill no)
			(layer "F.CrtYd")
		)
		(fp_rect
			(start 0.3 0.15)
			(end -0.301 -0.149)
			(stroke
				(width 0.15)
				(type solid)
			)
			(fill no)
			(layer "F.Fab")
		)
		(pad "" smd roundrect
			(at -0.349 -0.002 180)
			(size 0.318 0.36)
			(layers "F.Paste")
			(roundrect_rratio 0.25)
		)
		(pad "" smd roundrect
			(at 0.341 -0.002 180)
			(size 0.318 0.36)
			(layers "F.Paste")
			(roundrect_rratio 0.25)
		)
		(pad "1" smd roundrect
			(at -0.321 -0.002 180)
			(size 0.46 0.4)
			(layers "F.Cu" "F.Mask")
			(roundrect_rratio 0.25)
			(net 36 "GND")
			(pintype "passive")
		)
		(pad "2" smd roundrect
			(at 0.32 -0.002 180)
			(size 0.46 0.4)
			(layers "F.Cu" "F.Mask")
			(roundrect_rratio 0.25)
			(net 188 "VDD2")
			(pintype "passive")
		)
	)
	(footprint "antmicro-footprints:C_0201"
		(layer "F.Cu")
		(at 155.855 89.75 -90)
		(descr "Capacitor SMD 0201")
		(tags "capacitor SMD 0201")
		(property "Reference" "C27"
			(at -1.1 -1.22 90)
			(layer "F.SilkS")
			(effects
				(font
					(size 0.7 0.7)
					(thickness 0.15)
				)
				(justify right bottom)
			)
		)
		(property "Value" "C_100n_0201"
			(at 0 1.4 90)
			(layer "F.Fab")
			(effects
				(font
					(size 0.7 0.7)
					(thickness 0.15)
				)
				(justify right bottom)
			)
		)
		(property "Description" " "
			(at 0 0 270)
			(layer "F.Fab")
			(hide yes)
			(effects
				(font
					(size 1.27 1.27)
					(thickness 0.15)
				)
			)
		)
		(property "Author" "Antmicro"
			(at 66.105 245.605 0)
			(layer "F.Fab")
			(hide yes)
			(effects
				(font
					(size 1 1)
					(thickness 0.15)
				)
			)
		)
		(property "Dielectric" ""
			(at 66.105 245.605 0)
			(layer "F.Fab")
			(hide yes)
			(effects
				(font
					(size 1 1)
					(thickness 0.15)
				)
			)
		)
		(property "License" "Apache-2.0"
			(at 66.105 245.605 0)
			(layer "F.Fab")
			(hide yes)
			(effects
				(font
					(size 1 1)
					(thickness 0.15)
				)
			)
		)
		(property "MPN" "CC0201KRX6S5BB104"
			(at 66.105 245.605 0)
			(layer "F.Fab")
			(hide yes)
			(effects
				(font
					(size 1 1)
					(thickness 0.15)
				)
			)
		)
		(property "Manufacturer" "YAGEO"
			(at 66.105 245.605 0)
			(layer "F.Fab")
			(hide yes)
			(effects
				(font
					(size 1 1)
					(thickness 0.15)
				)
			)
		)
		(property "Val" "100n"
			(at 66.105 245.605 0)
			(layer "F.Fab")
			(hide yes)
			(effects
				(font
					(size 1 1)
					(thickness 0.15)
				)
			)
		)
		(property "Voltage" ""
			(at 66.105 245.605 0)
			(layer "F.Fab")
			(hide yes)
			(effects
				(font
					(size 1 1)
					(thickness 0.15)
				)
			)
		)
		(sheetname "LPDDR4")
		(sheetfile "lpddr4.kicad_sch")
		(attr smd)
		(fp_rect
			(start -0.72 -0.38)
			(end 0.72 0.38)
			(stroke
				(width 0.05)
				(type solid)
			)
			(fill no)
			(layer "F.CrtYd")
		)
		(fp_rect
			(start 0.3 0.15)
			(end -0.301 -0.149)
			(stroke
				(width 0.15)
				(type solid)
			)
			(fill no)
			(layer "F.Fab")
		)
		(pad "" smd roundrect
			(at -0.349 -0.002 270)
			(size 0.318 0.36)
			(layers "F.Paste")
			(roundrect_rratio 0.25)
		)
		(pad "" smd roundrect
			(at 0.341 -0.002 270)
			(size 0.318 0.36)
			(layers "F.Paste")
			(roundrect_rratio 0.25)
		)
		(pad "1" smd roundrect
			(at -0.321 -0.002 270)
			(size 0.46 0.4)
			(layers "F.Cu" "F.Mask")
			(roundrect_rratio 0.25)
			(net 36 "GND")
			(pintype "passive")
		)
		(pad "2" smd roundrect
			(at 0.32 -0.002 270)
			(size 0.46 0.4)
			(layers "F.Cu" "F.Mask")
			(roundrect_rratio 0.25)
			(net 187 "VDD1")
			(pintype "passive")
		)
	)
	(footprint "antmicro-footprints:C_0201"
		(layer "F.Cu")
		(at 142.925 89.1 -90)
		(descr "Capacitor SMD 0201")
		(tags "capacitor SMD 0201")
		(property "Reference" "C31"
			(at -0.55 0.45 90)
			(layer "F.SilkS")
			(effects
				(font
					(size 0.7 0.7)
					(thickness 0.15)
				)
				(justify right bottom)
			)
		)
		(property "Value" "C_100n_0201"
			(at 0 1.4 90)
			(layer "F.Fab")
			(effects
				(font
					(size 0.7 0.7)
					(thickness 0.15)
				)
				(justify right bottom)
			)
		)
		(property "Description" " "
			(at 0 0 270)
			(layer "F.Fab")
			(hide yes)
			(effects
				(font
					(size 1.27 1.27)
					(thickness 0.15)
				)
			)
		)
		(property "Author" "Antmicro"
			(at 53.825 232.025 0)
			(layer "F.Fab")
			(hide yes)
			(effects
				(font
					(size 1 1)
					(thickness 0.15)
				)
			)
		)
		(property "Dielectric" ""
			(at 53.825 232.025 0)
			(layer "F.Fab")
			(hide yes)
			(effects
				(font
					(size 1 1)
					(thickness 0.15)
				)
			)
		)
		(property "License" "Apache-2.0"
			(at 53.825 232.025 0)
			(layer "F.Fab")
			(hide yes)
			(effects
				(font
					(size 1 1)
					(thickness 0.15)
				)
			)
		)
		(property "MPN" "CC0201KRX6S5BB104"
			(at 53.825 232.025 0)
			(layer "F.Fab")
			(hide yes)
			(effects
				(font
					(size 1 1)
					(thickness 0.15)
				)
			)
		)
		(property "Manufacturer" "YAGEO"
			(at 53.825 232.025 0)
			(layer "F.Fab")
			(hide yes)
			(effects
				(font
					(size 1 1)
					(thickness 0.15)
				)
			)
		)
		(property "Val" "100n"
			(at 53.825 232.025 0)
			(layer "F.Fab")
			(hide yes)
			(effects
				(font
					(size 1 1)
					(thickness 0.15)
				)
			)
		)
		(property "Voltage" ""
			(at 53.825 232.025 0)
			(layer "F.Fab")
			(hide yes)
			(effects
				(font
					(size 1 1)
					(thickness 0.15)
				)
			)
		)
		(sheetname "LPDDR4")
		(sheetfile "lpddr4.kicad_sch")
		(attr smd)
		(fp_rect
			(start -0.72 -0.38)
			(end 0.72 0.38)
			(stroke
				(width 0.05)
				(type solid)
			)
			(fill no)
			(layer "F.CrtYd")
		)
		(fp_rect
			(start 0.3 0.15)
			(end -0.301 -0.149)
			(stroke
				(width 0.15)
				(type solid)
			)
			(fill no)
			(layer "F.Fab")
		)
		(pad "" smd roundrect
			(at -0.349 -0.002 270)
			(size 0.318 0.36)
			(layers "F.Paste")
			(roundrect_rratio 0.25)
		)
		(pad "" smd roundrect
			(at 0.341 -0.002 270)
			(size 0.318 0.36)
			(layers "F.Paste")
			(roundrect_rratio 0.25)
		)
		(pad "1" smd roundrect
			(at -0.321 -0.002 270)
			(size 0.46 0.4)
			(layers "F.Cu" "F.Mask")
			(roundrect_rratio 0.25)
			(net 36 "GND")
			(pintype "passive")
		)
		(pad "2" smd roundrect
			(at 0.32 -0.002 270)
			(size 0.46 0.4)
			(layers "F.Cu" "F.Mask")
			(roundrect_rratio 0.25)
			(net 187 "VDD1")
			(pintype "passive")
		)
	)
	(footprint "antmicro-footprints:BGA-264-200_10x14.5mm_Layout12x22_P0.8x0.65mm"
		(locked yes)
		(layer "F.Cu")
		(at 149.375 86.125 180)
		(descr "http://www.issi.com/WW/pdf/43-46LQ32256A-AL.pdf")
		(property "Reference" "U1"
			(at 5.2 7.575 180)
			(layer "F.SilkS")
			(effects
				(font
					(size 0.7 0.7)
					(thickness 0.15)
				)
				(justify left bottom)
			)
		)
		(property "Value" "MT53E1G32D2NP-046"
			(at -5.5 9 180)
			(layer "F.Fab")
			(effects
				(font
					(size 0.7 0.7)
					(thickness 0.15)
				)
				(justify left bottom)
			)
		)
		(property "Description" "DRAM, Mobile LPDDR4, 32 Gbit, 1G x 32bit, 2.133 GHz, WFBGA, 200 Pins"
			(at 0 0 180)
			(layer "F.Fab")
			(hide yes)
			(effects
				(font
					(size 1.27 1.27)
					(thickness 0.15)
				)
			)
		)
		(property "Author" "Antmicro"
			(at 298.75 172.25 0)
			(layer "F.Fab")
			(hide yes)
			(effects
				(font
					(size 1 1)
					(thickness 0.15)
				)
			)
		)
		(property "License" "Apache-2.0"
			(at 298.75 172.25 0)
			(layer "F.Fab")
			(hide yes)
			(effects
				(font
					(size 1 1)
					(thickness 0.15)
				)
			)
		)
		(property "MPN" "MT53E1G32D2NP-046 WT:A"
			(at 298.75 172.25 0)
			(layer "F.Fab")
			(hide yes)
			(effects
				(font
					(size 1 1)
					(thickness 0.15)
				)
			)
		)
		(property "Manufacturer" "Micron Technology"
			(at 298.75 172.25 0)
			(layer "F.Fab")
			(hide yes)
			(effects
				(font
					(size 1 1)
					(thickness 0.15)
				)
			)
		)
		(sheetname "LPDDR4")
		(sheetfile "lpddr4.kicad_sch")
		(attr smd)
		(fp_line
			(start 5.115 7.352)
			(end -5.106 7.352)
			(stroke
				(width 0.15)
				(type solid)
			)
			(layer "F.SilkS")
		)
		(fp_line
			(start 5.115 -7.369)
			(end 5.115 7.352)
			(stroke
				(width 0.15)
				(type solid)
			)
			(layer "F.SilkS")
		)
		(fp_line
			(start -4.106 -7.369)
			(end 5.115 -7.369)
			(stroke
				(width 0.15)
				(type solid)
			)
			(layer "F.SilkS")
		)
		(fp_line
			(start -5.106 7.352)
			(end -5.106 -6.369)
			(stroke
				(width 0.15)
				(type solid)
			)
			(layer "F.SilkS")
		)
		(fp_circle
			(center -5.1 -7.35)
			(end -5.05 -7.35)
			(stroke
				(width 0.15)
				(type solid)
			)
			(fill yes)
			(layer "F.SilkS")
		)
		(fp_rect
			(start -5.25 -7.5)
			(end 5.248 7.499)
			(stroke
				(width 0.05)
				(type solid)
			)
			(fill no)
			(layer "F.CrtYd")
		)
		(fp_line
			(start 5.004 7.241)
			(end -4.996 7.241)
			(stroke
				(width 0.15)
				(type solid)
			)
			(layer "F.Fab")
		)
		(fp_line
			(start 5.004 -7.258)
			(end 5.004 7.241)
			(stroke
				(width 0.15)
				(type solid)
			)
			(layer "F.Fab")
		)
		(fp_line
			(start -3.996 -7.258)
			(end 5.004 -7.258)
			(stroke
				(width 0.15)
				(type solid)
			)
			(layer "F.Fab")
		)
		(fp_line
			(start -4.996 7.241)
			(end -4.996 -6.258)
			(stroke
				(width 0.15)
				(type solid)
			)
			(layer "F.Fab")
		)
		(fp_line
			(start -4.996 -6.258)
			(end -3.996 -7.258)
			(stroke
				(width 0.15)
				(type solid)
			)
			(layer "F.Fab")
		)
		(fp_text user "License: Apache-2.0"
			(at -5.5 12.75 180)
			(layer "F.Fab")
			(effects
				(font
					(size 0.7 0.7)
					(thickness 0.15)
				)
				(justify left bottom)
			)
		)
		(fp_text user "Author: Antmicro"
			(at -5.5 11.5 180)
			(layer "F.Fab")
			(effects
				(font
					(size 0.7 0.7)
					(thickness 0.15)
				)
				(justify left bottom)
			)
		)
		(fp_text user "${REFERENCE}"
			(at -5.5 10.25 180)
			(layer "F.Fab")
			(effects
				(font
					(size 0.7 0.7)
					(thickness 0.15)
				)
				(justify left bottom)
			)
		)
		(pad "A1" smd circle
			(at -4.396 -6.834 180)
			(size 0.27 0.27)
			(layers "F.Cu" "F.Mask" "F.Paste")
			(net 162 "unconnected-(U1A-DNU-PadA1)")
			(pinfunction "DNU")
			(pintype "no_connect")
		)
		(pad "A2" smd circle
			(at -3.596 -6.834 180)
			(size 0.27 0.27)
			(layers "F.Cu" "F.Mask" "F.Paste")
			(net 163 "unconnected-(U1A-DNU-PadA2)")
			(pinfunction "DNU")
			(pintype "no_connect")
		)
		(pad "A3" smd circle
			(at -2.795 -6.834 180)
			(size 0.27 0.27)
			(layers "F.Cu" "F.Mask" "F.Paste")
			(net 36 "GND")
			(pinfunction "VSS")
			(pintype "passive")
		)
		(pad "A4" smd circle
			(at -1.996 -6.834 180)
			(size 0.27 0.27)
			(layers "F.Cu" "F.Mask" "F.Paste")
			(net 188 "VDD2")
			(pinfunction "VDD2")
			(pintype "power_in")
		)
		(pad "A5" smd circle
			(at -1.196 -6.834 180)
			(size 0.27 0.27)
			(layers "F.Cu" "F.Mask" "F.Paste")
			(net 161 "Net-(U1A-ZQ0)")
			(pinfunction "ZQ0")
			(pintype "input")
		)
		(pad "A8" smd circle
			(at 1.205 -6.834 180)
			(size 0.27 0.27)
			(layers "F.Cu" "F.Mask" "F.Paste")
			(net 164 "unconnected-(U1B-NC-PadA8)")
			(pinfunction "NC")
			(pintype "no_connect")
		)
		(pad "A9" smd circle
			(at 2.004 -6.834 180)
			(size 0.27 0.27)
			(layers "F.Cu" "F.Mask" "F.Paste")
			(net 188 "VDD2")
			(pinfunction "VDD2")
			(pintype "passive")
		)
		(pad "A10" smd circle
			(at 2.805 -6.834 180)
			(size 0.27 0.27)
			(layers "F.Cu" "F.Mask" "F.Paste")
			(net 36 "GND")
			(pinfunction "VSS")
			(pintype "power_in")
		)
		(pad "A11" smd circle
			(at 3.604 -6.834 180)
			(size 0.27 0.27)
			(layers "F.Cu" "F.Mask" "F.Paste")
			(net 165 "unconnected-(U1A-DNU-PadA11)")
			(pinfunction "DNU")
			(pintype "no_connect")
		)
		(pad "A12" smd circle
			(at 4.405 -6.834 180)
			(size 0.27 0.27)
			(layers "F.Cu" "F.Mask" "F.Paste")
			(net 166 "unconnected-(U1A-DNU-PadA12)")
			(pinfunction "DNU")
			(pintype "no_connect")
		)
		(pad "AA1" smd circle
			(at -4.396 6.166 180)
			(size 0.27 0.27)
			(layers "F.Cu" "F.Mask" "F.Paste")
			(net 167 "unconnected-(U1B-DNU-PadAA1)")
			(pinfunction "DNU")
			(pintype "no_connect")
		)
		(pad "AA2" smd circle
			(at -3.596 6.166 180)
			(size 0.27 0.27)
			(layers "F.Cu" "F.Mask" "F.Paste")
			(net 168 "unconnected-(U1B-DQ0_B-PadAA2)")
			(pinfunction "DQ0_B")
			(pintype "bidirectional+no_connect")
		)
		(pad "AA3" smd circle
			(at -2.795 6.166 180)
			(size 0.27 0.27)
			(layers "F.Cu" "F.Mask" "F.Paste")
			(net 189 "VDDQ")
			(pinfunction "VDDQ")
			(pintype "passive")
		)
		(pad "AA4" smd circle
			(at -1.996 6.166 180)
			(size 0.27 0.27)
			(layers "F.Cu" "F.Mask" "F.Paste")
			(net 169 "unconnected-(U1B-DQ7_B-PadAA4)")
			(pinfunction "DQ7_B")
			(pintype "bidirectional+no_connect")
		)
		(pad "AA5" smd circle
			(at -1.196 6.166 180)
			(size 0.27 0.27)
			(layers "F.Cu" "F.Mask" "F.Paste")
			(net 189 "VDDQ")
			(pinfunction "VDDQ")
			(pintype "passive")
		)
		(pad "AA8" smd circle
			(at 1.205 6.166 180)
			(size 0.27 0.27)
			(layers "F.Cu" "F.Mask" "F.Paste")
			(net 189 "VDDQ")
			(pinfunction "VDDQ")
			(pintype "passive")
		)
		(pad "AA9" smd circle
			(at 2.004 6.166 180)
			(size 0.27 0.27)
			(layers "F.Cu" "F.Mask" "F.Paste")
			(net 170 "unconnected-(U1B-DQ15_B-PadAA9)")
			(pinfunction "DQ15_B")
			(pintype "bidirectional+no_connect")
		)
		(pad "AA10" smd circle
			(at 2.805 6.166 180)
			(size 0.27 0.27)
			(layers "F.Cu" "F.Mask" "F.Paste")
			(net 189 "VDDQ")
			(pinfunction "VDDQ")
			(pintype "power_in")
		)
		(pad "AA11" smd circle
			(at 3.604 6.166 180)
			(size 0.27 0.27)
			(layers "F.Cu" "F.Mask" "F.Paste")
			(net 171 "unconnected-(U1B-DQ8_B-PadAA11)")
			(pinfunction "DQ8_B")
			(pintype "bidirectional+no_connect")
		)
		(pad "AA12" smd circle
			(at 4.405 6.166 180)
			(size 0.27 0.27)
			(layers "F.Cu" "F.Mask" "F.Paste")
			(net 172 "unconnected-(U1B-DNU-PadAA12)")
			(pinfunction "DNU")
			(pintype "no_connect")
		)
		(pad "AB1" smd circle
			(at -4.396 6.817 180)
			(size 0.27 0.27)
			(layers "F.Cu" "F.Mask" "F.Paste")
			(net 173 "unconnected-(U1B-DNU-PadAB1)")
			(pinfunction "DNU")
			(pintype "no_connect")
		)
		(pad "AB2" smd circle
			(at -3.596 6.817 180)
			(size 0.27 0.27)
			(layers "F.Cu" "F.Mask" "F.Paste")
			(net 174 "unconnected-(U1B-DNU-PadAB2)")
			(pinfunction "DNU")
			(pintype "no_connect")
		)
		(pad "AB3" smd circle
			(at -2.795 6.817 180)
			(size 0.27 0.27)
			(layers "F.Cu" "F.Mask" "F.Paste")
			(net 36 "GND")
			(pinfunction "VSS")
			(pintype "passive")
		)
		(pad "AB4" smd circle
			(at -1.996 6.817 180)
			(size 0.27 0.27)
			(layers "F.Cu" "F.Mask" "F.Paste")
			(net 188 "VDD2")
			(pinfunction "VDD2")
			(pintype "power_in")
		)
		(pad "AB5" smd circle
			(at -1.196 6.817 180)
			(size 0.27 0.27)
			(layers "F.Cu" "F.Mask" "F.Paste")
			(net 36 "GND")
			(pinfunction "VSS")
			(pintype "passive")
		)
		(pad "AB8" smd circle
			(at 1.205 6.817 180)
			(size 0.27 0.27)
			(layers "F.Cu" "F.Mask" "F.Paste")
			(net 36 "GND")
			(pinfunction "VSS")
			(pintype "passive")
		)
		(pad "AB9" smd circle
			(at 2.004 6.817 180)
			(size 0.27 0.27)
			(layers "F.Cu" "F.Mask" "F.Paste")
			(net 188 "VDD2")
			(pinfunction "VDD2")
			(pintype "passive")
		)
		(pad "AB10" smd circle
			(at 2.805 6.817 180)
			(size 0.27 0.27)
			(layers "F.Cu" "F.Mask" "F.Paste")
			(net 36 "GND")
			(pinfunction "VSS")
			(pintype "power_in")
		)
		(pad "AB11" smd circle
			(at 3.604 6.817 180)
			(size 0.27 0.27)
			(layers "F.Cu" "F.Mask" "F.Paste")
			(net 175 "unconnected-(U1B-DNU-PadAB11)")
			(pinfunction "DNU")
			(pintype "no_connect")
		)
		(pad "AB12" smd circle
			(at 4.405 6.817 180)
			(size 0.27 0.27)
			(layers "F.Cu" "F.Mask" "F.Paste")
			(net 176 "unconnected-(U1B-DNU-PadAB12)")
			(pinfunction "DNU")
			(pintype "no_connect")
		)
		(pad "B1" smd circle
			(at -4.396 -6.183 180)
			(size 0.27 0.27)
			(layers "F.Cu" "F.Mask" "F.Paste")
			(net 177 "unconnected-(U1A-DNU-PadB1)")
			(pinfunction "DNU")
			(pintype "no_connect")
		)
		(pad "B2" smd circle
			(at -3.596 -6.183 180)
			(size 0.27 0.27)
			(layers "F.Cu" "F.Mask" "F.Paste")
			(net 190 "DQ00_A")
			(pinfunction "DQ0_A")
			(pintype "bidirectional")
		)
		(pad "B3" smd circle
			(at -2.795 -6.183 180)
			(size 0.27 0.27)
			(layers "F.Cu" "F.Mask" "F.Paste")
			(net 189 "VDDQ")
			(pinfunction "VDDQ")
			(pintype "passive")
		)
		(pad "B4" smd circle
			(at -1.996 -6.183 180)
			(size 0.27 0.27)
			(layers "F.Cu" "F.Mask" "F.Paste")
			(net 198 "DQ07_A")
			(pinfunction "DQ7_A")
			(pintype "bidirectional")
		)
		(pad "B5" smd circle
			(at -1.196 -6.183 180)
			(size 0.27 0.27)
			(layers "F.Cu" "F.Mask" "F.Paste")
			(net 189 "VDDQ")
			(pinfunction "VDDQ")
			(pintype "passive")
		)
		(pad "B8" smd circle
			(at 1.205 -6.183 180)
			(size 0.27 0.27)
			(layers "F.Cu" "F.Mask" "F.Paste")
			(net 189 "VDDQ")
			(pinfunction "VDDQ")
			(pintype "passive")
		)
		(pad "B9" smd circle
			(at 2.004 -6.183 180)
			(size 0.27 0.27)
			(layers "F.Cu" "F.Mask" "F.Paste")
			(net 208 "DQ15_A")
			(pinfunction "DQ15_A")
			(pintype "bidirectional")
		)
		(pad "B10" smd circle
			(at 2.805 -6.183 180)
			(size 0.27 0.27)
			(layers "F.Cu" "F.Mask" "F.Paste")
			(net 189 "VDDQ")
			(pinfunction "VDDQ")
			(pintype "power_in")
		)
		(pad "B11" smd circle
			(at 3.604 -6.183 180)
			(size 0.27 0.27)
			(layers "F.Cu" "F.Mask" "F.Paste")
			(net 212 "DQ08_A")
			(pinfunction "DQ8_A")
			(pintype "bidirectional")
		)
		(pad "B12" smd circle
			(at 4.405 -6.183 180)
			(size 0.27 0.27)
			(layers "F.Cu" "F.Mask" "F.Paste")
			(net 178 "unconnected-(U1A-DNU-PadB12)")
			(pinfunction "DNU")
			(pintype "no_connect")
		)
		(pad "C1" smd circle
			(at -4.396 -5.534 180)
			(size 0.27 0.27)
			(layers "F.Cu" "F.Mask" "F.Paste")
			(net 36 "GND")
			(pinfunction "VSS")
			(pintype "passive")
		)
		(pad "C2" smd circle
			(at -3.596 -5.534 180)
			(size 0.27 0.27)
			(layers "F.Cu" "F.Mask" "F.Paste")
			(net 191 "DQ01_A")
			(pinfunction "DQ1_A")
			(pintype "bidirectional")
		)
		(pad "C3" smd circle
			(at -2.795 -5.534 180)
			(size 0.27 0.27)
			(layers "F.Cu" "F.Mask" "F.Paste")
			(net 201 "DMI_0A")
			(pinfunction "DMI0_A")
			(pintype "bidirectional")
		)
		(pad "C4" smd circle
			(at -1.996 -5.534 180)
			(size 0.27 0.27)
			(layers "F.Cu" "F.Mask" "F.Paste")
			(net 202 "DQ06_A")
			(pinfunction "DQ6_A")
			(pintype "bidirectional")
		)
		(pad "C5" smd circle
			(at -1.196 -5.534 180)
			(size 0.27 0.27)
			(layers "F.Cu" "F.Mask" "F.Paste")
			(net 36 "GND")
			(pinfunction "VSS")
			(pintype "passive")
		)
		(pad "C8" smd circle
			(at 1.205 -5.534 180)
			(size 0.27 0.27)
			(layers "F.Cu" "F.Mask" "F.Paste")
			(net 36 "GND")
			(pinfunction "VSS")
			(pintype "passive")
		)
		(pad "C9" smd circle
			(at 2.004 -5.534 180)
			(size 0.27 0.27)
			(layers "F.Cu" "F.Mask" "F.Paste")
			(net 207 "DQ14_A")
			(pinfunction "DQ14_A")
			(pintype "bidirectional")
		)
		(pad "C10" smd circle
			(at 2.805 -5.534 180)
			(size 0.27 0.27)
			(layers "F.Cu" "F.Mask" "F.Paste")
			(net 211 "DMI_1A")
			(pinfunction "DMI1_A")
			(pintype "bidirectional")
		)
		(pad "C11" smd circle
			(at 3.604 -5.534 180)
			(size 0.27 0.27)
			(layers "F.Cu" "F.Mask" "F.Paste")
			(net 213 "DQ09_A")
			(pinfunction "DQ9_A")
			(pintype "bidirectional")
		)
		(pad "C12" smd circle
			(at 4.405 -5.534 180)
			(size 0.27 0.27)
			(layers "F.Cu" "F.Mask" "F.Paste")
			(net 36 "GND")
			(pinfunction "VSS")
			(pintype "passive")
		)
		(pad "D1" smd circle
			(at -4.396 -4.883 180)
			(size 0.27 0.27)
			(layers "F.Cu" "F.Mask" "F.Paste")
			(net 189 "VDDQ")
			(pinfunction "VDDQ")
			(pintype "passive")
		)
		(pad "D2" smd circle
			(at -3.596 -4.883 180)
			(size 0.27 0.27)
			(layers "F.Cu" "F.Mask" "F.Paste")
			(net 36 "GND")
			(pinfunction "VSS")
			(pintype "passive")
		)
		(pad "D3" smd circle
			(at -2.795 -4.883 180)
			(size 0.27 0.27)
			(layers "F.Cu" "F.Mask" "F.Paste")
			(net 196 "DQ_S0_TA")
			(pinfunction "DQS0_T_A")
			(pintype "bidirectional")
		)
		(pad "D4" smd circle
			(at -1.996 -4.883 180)
			(size 0.27 0.27)
			(layers "F.Cu" "F.Mask" "F.Paste")
			(net 36 "GND")
			(pinfunction "VSS")
			(pintype "passive")
		)
		(pad "D5" smd circle
			(at -1.196 -4.883 180)
			(size 0.27 0.27)
			(layers "F.Cu" "F.Mask" "F.Paste")
			(net 189 "VDDQ")
			(pinfunction "VDDQ")
			(pintype "passive")
		)
		(pad "D8" smd circle
			(at 1.205 -4.883 180)
			(size 0.27 0.27)
			(layers "F.Cu" "F.Mask" "F.Paste")
			(net 189 "VDDQ")
			(pinfunction "VDDQ")
			(pintype "passive")
		)
		(pad "D9" smd circle
			(at 2.004 -4.883 180)
			(size 0.27 0.27)
			(layers "F.Cu" "F.Mask" "F.Paste")
			(net 36 "GND")
			(pinfunction "VSS")
			(pintype "passive")
		)
		(pad "D10" smd circle
			(at 2.805 -4.883 180)
			(size 0.27 0.27)
			(layers "F.Cu" "F.Mask" "F.Paste")
			(net 209 "DQ_S1_TA")
			(pinfunction "DQS1_T_A")
			(pintype "bidirectional")
		)
		(pad "D11" smd circle
			(at 3.604 -4.883 180)
			(size 0.27 0.27)
			(layers "F.Cu" "F.Mask" "F.Paste")
			(net 36 "GND")
			(pinfunction "VSS")
			(pintype "passive")
		)
		(pad "D12" smd circle
			(at 4.405 -4.883 180)
			(size 0.27 0.27)
			(layers "F.Cu" "F.Mask" "F.Paste")
			(net 189 "VDDQ")
			(pinfunction "VDDQ")
			(pintype "passive")
		)
		(pad "E1" smd circle
			(at -4.396 -4.233 180)
			(size 0.27 0.27)
			(layers "F.Cu" "F.Mask" "F.Paste")
			(net 36 "GND")
			(pinfunction "VSS")
			(pintype "passive")
		)
		(pad "E2" smd circle
			(at -3.596 -4.233 180)
			(size 0.27 0.27)
			(layers "F.Cu" "F.Mask" "F.Paste")
			(net 193 "DQ02_A")
			(pinfunction "DQ2_A")
			(pintype "bidirectional")
		)
		(pad "E3" smd circle
			(at -2.795 -4.233 180)
			(size 0.27 0.27)
			(layers "F.Cu" "F.Mask" "F.Paste")
			(net 197 "DQ_S0_CA")
			(pinfunction "DQS0_C_A")
			(pintype "bidirectional")
		)
		(pad "E4" smd circle
			(at -1.996 -4.233 180)
			(size 0.27 0.27)
			(layers "F.Cu" "F.Mask" "F.Paste")
			(net 203 "DQ05_A")
			(pinfunction "DQ5_A")
			(pintype "bidirectional")
		)
		(pad "E5" smd circle
			(at -1.196 -4.233 180)
			(size 0.27 0.27)
			(layers "F.Cu" "F.Mask" "F.Paste")
			(net 36 "GND")
			(pinfunction "VSS")
			(pintype "passive")
		)
		(pad "E8" smd circle
			(at 1.205 -4.233 180)
			(size 0.27 0.27)
			(layers "F.Cu" "F.Mask" "F.Paste")
			(net 36 "GND")
			(pinfunction "VSS")
			(pintype "passive")
		)
		(pad "E9" smd circle
			(at 2.004 -4.233 180)
			(size 0.27 0.27)
			(layers "F.Cu" "F.Mask" "F.Paste")
			(net 206 "DQ13_A")
			(pinfunction "DQ13_A")
			(pintype "bidirectional")
		)
		(pad "E10" smd circle
			(at 2.805 -4.233 180)
			(size 0.27 0.27)
			(layers "F.Cu" "F.Mask" "F.Paste")
			(net 210 "DQ_S1_CA")
			(pinfunction "DQS1_C_A")
			(pintype "bidirectional")
		)
		(pad "E11" smd circle
			(at 3.604 -4.233 180)
			(size 0.27 0.27)
			(layers "F.Cu" "F.Mask" "F.Paste")
			(net 215 "DQ10_A")
			(pinfunction "DQ10_A")
			(pintype "bidirectional")
		)
		(pad "E12" smd circle
			(at 4.405 -4.233 180)
			(size 0.27 0.27)
			(layers "F.Cu" "F.Mask" "F.Paste")
			(net 36 "GND")
			(pinfunction "VSS")
			(pintype "passive")
		)
		(pad "F1" smd circle
			(at -4.396 -3.584 180)
			(size 0.27 0.27)
			(layers "F.Cu" "F.Mask" "F.Paste")
			(net 187 "VDD1")
			(pinfunction "VDD1")
			(pintype "power_in")
		)
		(pad "F2" smd circle
			(at -3.596 -3.584 180)
			(size 0.27 0.27)
			(layers "F.Cu" "F.Mask" "F.Paste")
			(net 195 "DQ03_A")
			(pinfunction "DQ3_A")
			(pintype "bidirectional")
		)
		(pad "F3" smd circle
			(at -2.795 -3.584 180)
			(size 0.27 0.27)
			(layers "F.Cu" "F.Mask" "F.Paste")
			(net 189 "VDDQ")
			(pinfunction "VDDQ")
			(pintype "passive")
		)
		(pad "F4" smd circle
			(at -1.996 -3.584 180)
			(size 0.27 0.27)
			(layers "F.Cu" "F.Mask" "F.Paste")
			(net 204 "DQ04_A")
			(pinfunction "DQ4_A")
			(pintype "bidirectional")
		)
		(pad "F5" smd circle
			(at -1.196 -3.584 180)
			(size 0.27 0.27)
			(layers "F.Cu" "F.Mask" "F.Paste")
			(net 188 "VDD2")
			(pinfunction "VDD2")
			(pintype "passive")
		)
		(pad "F8" smd circle
			(at 1.205 -3.584 180)
			(size 0.27 0.27)
			(layers "F.Cu" "F.Mask" "F.Paste")
			(net 188 "VDD2")
			(pinfunction "VDD2")
			(pintype "passive")
		)
		(pad "F9" smd circle
			(at 2.004 -3.584 180)
			(size 0.27 0.27)
			(layers "F.Cu" "F.Mask" "F.Paste")
			(net 205 "DQ12_A")
			(pinfunction "DQ12_A")
			(pintype "bidirectional")
		)
		(pad "F10" smd circle
			(at 2.805 -3.584 180)
			(size 0.27 0.27)
			(layers "F.Cu" "F.Mask" "F.Paste")
			(net 189 "VDDQ")
			(pinfunction "VDDQ")
			(pintype "passive")
		)
		(pad "F11" smd circle
			(at 3.604 -3.584 180)
			(size 0.27 0.27)
			(layers "F.Cu" "F.Mask" "F.Paste")
			(net 217 "DQ11_A")
			(pinfunction "DQ11_A")
			(pintype "bidirectional")
		)
		(pad "F12" smd circle
			(at 4.405 -3.584 180)
			(size 0.27 0.27)
			(layers "F.Cu" "F.Mask" "F.Paste")
			(net 187 "VDD1")
			(pinfunction "VDD1")
			(pintype "passive")
		)
		(pad "G1" smd circle
			(at -4.396 -2.934 180)
			(size 0.27 0.27)
			(layers "F.Cu" "F.Mask" "F.Paste")
			(net 36 "GND")
			(pinfunction "VSS")
			(pintype "passive")
		)
		(pad "G2" smd circle
			(at -3.596 -2.934 180)
			(size 0.27 0.27)
			(layers "F.Cu" "F.Mask" "F.Paste")
			(net 158 "Net-(U1A-ODT_CA_A)")
			(pinfunction "ODT_CA_A")
			(pintype "input")
		)
		(pad "G3" smd circle
			(at -2.795 -2.934 180)
			(size 0.27 0.27)
			(layers "F.Cu" "F.Mask" "F.Paste")
			(net 36 "GND")
			(pinfunction "VSS")
			(pintype "passive")
		)
		(pad "G4" smd circle
			(at -1.996 -2.934 180)
			(size 0.27 0.27)
			(layers "F.Cu" "F.Mask" "F.Paste")
			(net 187 "VDD1")
			(pinfunction "VDD1")
			(pintype "passive")
		)
		(pad "G5" smd circle
			(at -1.196 -2.934 180)
			(size 0.27 0.27)
			(layers "F.Cu" "F.Mask" "F.Paste")
			(net 36 "GND")
			(pinfunction "VSS")
			(pintype "passive")
		)
		(pad "G8" smd circle
			(at 1.205 -2.934 180)
			(size 0.27 0.27)
			(layers "F.Cu" "F.Mask" "F.Paste")
			(net 36 "GND")
			(pinfunction "VSS")
			(pintype "passive")
		)
		(pad "G9" smd circle
			(at 2.004 -2.934 180)
			(size 0.27 0.27)
			(layers "F.Cu" "F.Mask" "F.Paste")
			(net 187 "VDD1")
			(pinfunction "VDD1")
			(pintype "passive")
		)
		(pad "G10" smd circle
			(at 2.805 -2.934 180)
			(size 0.27 0.27)
			(layers "F.Cu" "F.Mask" "F.Paste")
			(net 36 "GND")
			(pinfunction "VSS")
			(pintype "passive")
		)
		(pad "G11" smd circle
			(at 3.604 -2.934 180)
			(size 0.27 0.27)
			(layers "F.Cu" "F.Mask" "F.Paste")
			(net 179 "unconnected-(U1B-NC-PadG11)")
			(pinfunction "NC")
			(pintype "no_connect")
		)
		(pad "G12" smd circle
			(at 4.405 -2.934 180)
			(size 0.27 0.27)
			(layers "F.Cu" "F.Mask" "F.Paste")
			(net 36 "GND")
			(pinfunction "VSS")
			(pintype "passive")
		)
		(pad "H1" smd circle
			(at -4.396 -2.283 180)
			(size 0.27 0.27)
			(layers "F.Cu" "F.Mask" "F.Paste")
			(net 188 "VDD2")
			(pinfunction "VDD2")
			(pintype "passive")
		)
		(pad "H2" smd circle
			(at -3.596 -2.283 180)
			(size 0.27 0.27)
			(layers "F.Cu" "F.Mask" "F.Paste")
			(net 192 "CA0_A")
			(pinfunction "CA0_A")
			(pintype "input")
		)
		(pad "H3" smd circle
			(at -2.795 -2.283 180)
			(size 0.27 0.27)
			(layers "F.Cu" "F.Mask" "F.Paste")
			(net 180 "unconnected-(U1A-NC-PadH3)")
			(pinfunction "NC")
			(pintype "no_connect")
		)
		(pad "H4" smd circle
			(at -1.996 -2.283 180)
			(size 0.27 0.27)
			(layers "F.Cu" "F.Mask" "F.Paste")
			(net 200 "CS0_A")
			(pinfunction "CS0_A")
			(pintype "input")
		)
		(pad "H5" smd circle
			(at -1.196 -2.283 180)
			(size 0.27 0.27)
			(layers "F.Cu" "F.Mask" "F.Paste")
			(net 188 "VDD2")
			(pinfunction "VDD2")
			(pintype "passive")
		)
		(pad "H8" smd circle
			(at 1.205 -2.283 180)
			(size 0.27 0.27)
			(layers "F.Cu" "F.Mask" "F.Paste")
			(net 188 "VDD2")
			(pinfunction "VDD2")
			(pintype "passive")
		)
		(pad "H9" smd circle
			(at 2.004 -2.283 180)
			(size 0.27 0.27)
			(layers "F.Cu" "F.Mask" "F.Paste")
			(net 218 "CA2_A")
			(pinfunction "CA2_A")
			(pintype "input")
		)
		(pad "H10" smd circle
			(at 2.805 -2.283 180)
			(size 0.27 0.27)
			(layers "F.Cu" "F.Mask" "F.Paste")
			(net 219 "CA3_A")
			(pinfunction "CA3_A")
			(pintype "input")
		)
		(pad "H11" smd circle
			(at 3.604 -2.283 180)
			(size 0.27 0.27)
			(layers "F.Cu" "F.Mask" "F.Paste")
			(net 220 "CA4_A")
			(pinfunction "CA4_A")
			(pintype "input")
		)
		(pad "H12" smd circle
			(at 4.405 -2.283 180)
			(size 0.27 0.27)
			(layers "F.Cu" "F.Mask" "F.Paste")
			(net 188 "VDD2")
			(pinfunction "VDD2")
			(pintype "passive")
		)
		(pad "J1" smd circle
			(at -4.396 -1.633 180)
			(size 0.27 0.27)
			(layers "F.Cu" "F.Mask" "F.Paste")
			(net 36 "GND")
			(pinfunction "VSS")
			(pintype "passive")
		)
		(pad "J2" smd circle
			(at -3.596 -1.633 180)
			(size 0.27 0.27)
			(layers "F.Cu" "F.Mask" "F.Paste")
			(net 194 "CA1_A")
			(pinfunction "CA1_A")
			(pintype "input")
		)
		(pad "J3" smd circle
			(at -2.795 -1.633 180)
			(size 0.27 0.27)
			(layers "F.Cu" "F.Mask" "F.Paste")
			(net 36 "GND")
			(pinfunction "VSS")
			(pintype "passive")
		)
		(pad "J4" smd circle
			(at -1.996 -1.633 180)
			(size 0.27 0.27)
			(layers "F.Cu" "F.Mask" "F.Paste")
			(net 199 "CKE0_A")
			(pinfunction "CKE0_A")
			(pintype "input")
		)
		(pad "J5" smd circle
			(at -1.196 -1.633 180)
			(size 0.27 0.27)
			(layers "F.Cu" "F.Mask" "F.Paste")
			(net 181 "unconnected-(U1A-NC-PadJ5)")
			(pinfunction "NC")
			(pintype "no_connect")
		)
		(pad "J8" smd circle
			(at 1.205 -1.633 180)
			(size 0.27 0.27)
			(layers "F.Cu" "F.Mask" "F.Paste")
			(net 216 "CK_T_A")
			(pinfunction "CK_T_A")
			(pintype "input")
		)
		(pad "J9" smd circle
			(at 2.004 -1.633 180)
			(size 0.27 0.27)
			(layers "F.Cu" "F.Mask" "F.Paste")
			(net 214 "CK_C_A")
			(pinfunction "CK_C_A")
			(pintype "input")
		)
		(pad "J10" smd circle
			(at 2.805 -1.633 180)
			(size 0.27 0.27)
			(layers "F.Cu" "F.Mask" "F.Paste")
			(net 36 "GND")
			(pinfunction "VSS")
			(pintype "passive")
		)
		(pad "J11" smd circle
			(at 3.604 -1.633 180)
			(size 0.27 0.27)
			(layers "F.Cu" "F.Mask" "F.Paste")
			(net 221 "CA5_A")
			(pinfunction "CA5_A")
			(pintype "input")
		)
		(pad "J12" smd circle
			(at 4.405 -1.633 180)
			(size 0.27 0.27)
			(layers "F.Cu" "F.Mask" "F.Paste")
			(net 36 "GND")
			(pinfunction "VSS")
			(pintype "passive")
		)
		(pad "K1" smd circle
			(at -4.396 -0.983 180)
			(size 0.27 0.27)
			(layers "F.Cu" "F.Mask" "F.Paste")
			(net 188 "VDD2")
			(pinfunction "VDD2")
			(pintype "passive")
		)
		(pad "K2" smd circle
			(at -3.596 -0.983 180)
			(size 0.27 0.27)
			(layers "F.Cu" "F.Mask" "F.Paste")
			(net 36 "GND")
			(pinfunction "VSS")
			(pintype "passive")
		)
		(pad "K3" smd circle
			(at -2.795 -0.983 180)
			(size 0.27 0.27)
			(layers "F.Cu" "F.Mask" "F.Paste")
			(net 188 "VDD2")
			(pinfunction "VDD2")
			(pintype "passive")
		)
		(pad "K4" smd circle
			(at -1.996 -0.983 180)
			(size 0.27 0.27)
			(layers "F.Cu" "F.Mask" "F.Paste")
			(net 36 "GND")
			(pinfunction "VSS")
			(pintype "passive")
		)
		(pad "K5" smd circle
			(at -1.196 -0.983 180)
			(size 0.27 0.27)
			(layers "F.Cu" "F.Mask" "F.Paste")
			(net 182 "unconnected-(U1A-NC-PadK5)")
			(pinfunction "NC")
			(pintype "no_connect")
		)
		(pad "K8" smd circle
			(at 1.205 -0.983 180)
			(size 0.27 0.27)
			(layers "F.Cu" "F.Mask" "F.Paste")
			(net 183 "unconnected-(U1A-NC-PadK8)")
			(pinfunction "NC")
			(pintype "no_connect")
		)
		(pad "K9" smd circle
			(at 2.004 -0.983 180)
			(size 0.27 0.27)
			(layers "F.Cu" "F.Mask" "F.Paste")
			(net 36 "GND")
			(pinfunction "VSS")
			(pintype "passive")
		)
		(pad "K10" smd circle
			(at 2.805 -0.983 180)
			(size 0.27 0.27)
			(layers "F.Cu" "F.Mask" "F.Paste")
			(net 188 "VDD2")
			(pinfunction "VDD2")
			(pintype "passive")
		)
		(pad "K11" smd circle
			(at 3.604 -0.983 180)
			(size 0.27 0.27)
			(layers "F.Cu" "F.Mask" "F.Paste")
			(net 36 "GND")
			(pinfunction "VSS")
			(pintype "passive")
		)
		(pad "K12" smd circle
			(at 4.405 -0.983 180)
			(size 0.27 0.27)
			(layers "F.Cu" "F.Mask" "F.Paste")
			(net 188 "VDD2")
			(pinfunction "VDD2")
			(pintype "passive")
		)
		(pad "N1" smd circle
			(at -4.396 0.966 180)
			(size 0.27 0.27)
			(layers "F.Cu" "F.Mask" "F.Paste")
			(net 188 "VDD2")
			(pinfunction "VDD2")
			(pintype "passive")
		)
		(pad "N2" smd circle
			(at -3.596 0.966 180)
			(size 0.27 0.27)
			(layers "F.Cu" "F.Mask" "F.Paste")
			(net 36 "GND")
			(pinfunction "VSS")
			(pintype "passive")
		)
		(pad "N3" smd circle
			(at -2.795 0.966 180)
			(size 0.27 0.27)
			(layers "F.Cu" "F.Mask" "F.Paste")
			(net 188 "VDD2")
			(pinfunction "VDD2")
			(pintype "passive")
		)
		(pad "N4" smd circle
			(at -1.996 0.966 180)
			(size 0.27 0.27)
			(layers "F.Cu" "F.Mask" "F.Paste")
			(net 36 "GND")
			(pinfunction "VSS")
			(pintype "passive")
		)
		(pad "N5" smd circle
			(at -1.196 0.966 180)
			(size 0.27 0.27)
			(layers "F.Cu" "F.Mask" "F.Paste")
			(net 184 "unconnected-(U1B-NC-PadN5)")
			(pinfunction "NC")
			(pintype "no_connect")
		)
		(pad "N8" smd circle
			(at 1.205 0.966 180)
			(size 0.27 0.27)
			(layers "F.Cu" "F.Mask" "F.Paste")
			(net 185 "unconnected-(U1B-NC-PadN8)")
			(pinfunction "NC")
			(pintype "no_connect")
		)
		(pad "N9" smd circle
			(at 2.004 0.966 180)
			(size 0.27 0.27)
			(layers "F.Cu" "F.Mask" "F.Paste")
			(net 36 "GND")
			(pinfunction "VSS")
			(pintype "passive")
		)
		(pad "N10" smd circle
			(at 2.805 0.966 180)
			(size 0.27 0.27)
			(layers "F.Cu" "F.Mask" "F.Paste")
			(net 188 "VDD2")
			(pinfunction "VDD2")
			(pintype "passive")
		)
		(pad "N11" smd circle
			(at 3.604 0.966 180)
			(size 0.27 0.27)
			(layers "F.Cu" "F.Mask" "F.Paste")
			(net 36 "GND")
			(pinfunction "VSS")
			(pintype "passive")
		)
		(pad "N12" smd circle
			(at 4.405 0.966 180)
			(size 0.27 0.27)
			(layers "F.Cu" "F.Mask" "F.Paste")
			(net 188 "VDD2")
			(pinfunction "VDD2")
			(pintype "passive")
		)
		(pad "P1" smd circle
			(at -4.396 1.616 180)
			(size 0.27 0.27)
			(layers "F.Cu" "F.Mask" "F.Paste")
			(net 36 "GND")
			(pinfunction "VSS")
			(pintype "passive")
		)
		(pad "P2" smd circle
			(at -3.596 1.616 180)
			(size 0.27 0.27)
			(layers "F.Cu" "F.Mask" "F.Paste")
			(net 186 "unconnected-(U1B-CA1_B-PadP2)")
			(pinfunction "CA1_B")
			(pintype "input+no_connect")
		)
		(pad "P3" smd circle
			(at -2.795 1.616 180)
			(size 0.27 0.27)
			(layers "F.Cu" "F.Mask" "F.Paste")
			(net 36 "GND")
			(pinfunction "VSS")
			(pintype "passive")
		)
		(pad "P4" smd circle
			(at -1.996 1.616 180)
			(size 0.27 0.27)
			(layers "F.Cu" "F.Mask" "F.Paste")
			(net 223 "unconnected-(U1B-CKE0_B-PadP4)")
			(pinfunction "CKE0_B")
			(pintype "input+no_connect")
		)
		(pad "P5" smd circle
			(at -1.196 1.616 180)
			(size 0.27 0.27)
			(layers "F.Cu" "F.Mask" "F.Paste")
			(net 224 "unconnected-(U1B-NC-PadP5)")
			(pinfunction "NC")
			(pintype "no_connect")
		)
		(pad "P8" smd circle
			(at 1.205 1.616 180)
			(size 0.27 0.27)
			(layers "F.Cu" "F.Mask" "F.Paste")
			(net 225 "unconnected-(U1B-CK_T_B-PadP8)")
			(pinfunction "CK_T_B")
			(pintype "input+no_connect")
		)
		(pad "P9" smd circle
			(at 2.004 1.616 180)
			(size 0.27 0.27)
			(layers "F.Cu" "F.Mask" "F.Paste")
			(net 226 "unconnected-(U1B-CK_C_B-PadP9)")
			(pinfunction "CK_C_B")
			(pintype "input+no_connect")
		)
		(pad "P10" smd circle
			(at 2.805 1.616 180)
			(size 0.27 0.27)
			(layers "F.Cu" "F.Mask" "F.Paste")
			(net 36 "GND")
			(pinfunction "VSS")
			(pintype "passive")
		)
		(pad "P11" smd circle
			(at 3.604 1.616 180)
			(size 0.27 0.27)
			(layers "F.Cu" "F.Mask" "F.Paste")
			(net 227 "unconnected-(U1B-CA5_B-PadP11)")
			(pinfunction "CA5_B")
			(pintype "input+no_connect")
		)
		(pad "P12" smd circle
			(at 4.405 1.616 180)
			(size 0.27 0.27)
			(layers "F.Cu" "F.Mask" "F.Paste")
			(net 36 "GND")
			(pinfunction "VSS")
			(pintype "passive")
		)
		(pad "R1" smd circle
			(at -4.396 2.266 180)
			(size 0.27 0.27)
			(layers "F.Cu" "F.Mask" "F.Paste")
			(net 188 "VDD2")
			(pinfunction "VDD2")
			(pintype "passive")
		)
		(pad "R2" smd circle
			(at -3.596 2.266 180)
			(size 0.27 0.27)
			(layers "F.Cu" "F.Mask" "F.Paste")
			(net 228 "unconnected-(U1B-CA0_B-PadR2)")
			(pinfunction "CA0_B")
			(pintype "input+no_connect")
		)
		(pad "R3" smd circle
			(at -2.795 2.266 180)
			(size 0.27 0.27)
			(layers "F.Cu" "F.Mask" "F.Paste")
			(net 231 "unconnected-(U1B-NC-PadR3)")
			(pinfunction "NC")
			(pintype "no_connect")
		)
		(pad "R4" smd circle
			(at -1.996 2.266 180)
			(size 0.27 0.27)
			(layers "F.Cu" "F.Mask" "F.Paste")
			(net 222 "CS0_B")
			(pinfunction "CS0_B")
			(pintype "input")
		)
		(pad "R5" smd circle
			(at -1.196 2.266 180)
			(size 0.27 0.27)
			(layers "F.Cu" "F.Mask" "F.Paste")
			(net 188 "VDD2")
			(pinfunction "VDD2")
			(pintype "passive")
		)
		(pad "R8" smd circle
			(at 1.205 2.266 180)
			(size 0.27 0.27)
			(layers "F.Cu" "F.Mask" "F.Paste")
			(net 188 "VDD2")
			(pinfunction "VDD2")
			(pintype "passive")
		)
		(pad "R9" smd circle
			(at 2.004 2.266 180)
			(size 0.27 0.27)
			(layers "F.Cu" "F.Mask" "F.Paste")
			(net 232 "unconnected-(U1B-CA2_B-PadR9)")
			(pinfunction "CA2_B")
			(pintype "input+no_connect")
		)
		(pad "R10" smd circle
			(at 2.805 2.266 180)
			(size 0.27 0.27)
			(layers "F.Cu" "F.Mask" "F.Paste")
			(net 233 "unconnected-(U1B-CA3_B-PadR10)")
			(pinfunction "CA3_B")
			(pintype "input+no_connect")
		)
		(pad "R11" smd circle
			(at 3.604 2.266 180)
			(size 0.27 0.27)
			(layers "F.Cu" "F.Mask" "F.Paste")
			(net 234 "unconnected-(U1B-CA4_B-PadR11)")
			(pinfunction "CA4_B")
			(pintype "input+no_connect")
		)
		(pad "R12" smd circle
			(at 4.405 2.266 180)
			(size 0.27 0.27)
			(layers "F.Cu" "F.Mask" "F.Paste")
			(net 188 "VDD2")
			(pinfunction "VDD2")
			(pintype "passive")
		)
		(pad "T1" smd circle
			(at -4.396 2.917 180)
			(size 0.27 0.27)
			(layers "F.Cu" "F.Mask" "F.Paste")
			(net 36 "GND")
			(pinfunction "VSS")
			(pintype "passive")
		)
		(pad "T2" smd circle
			(at -3.596 2.917 180)
			(size 0.27 0.27)
			(layers "F.Cu" "F.Mask" "F.Paste")
			(net 159 "Net-(U1B-ODT_CA_B)")
			(pinfunction "ODT_CA_B")
			(pintype "input")
		)
		(pad "T3" smd circle
			(at -2.795 2.917 180)
			(size 0.27 0.27)
			(layers "F.Cu" "F.Mask" "F.Paste")
			(net 36 "GND")
			(pinfunction "VSS")
			(pintype "passive")
		)
		(pad "T4" smd circle
			(at -1.996 2.917 180)
			(size 0.27 0.27)
			(layers "F.Cu" "F.Mask" "F.Paste")
			(net 187 "VDD1")
			(pinfunction "VDD1")
			(pintype "power_in")
		)
		(pad "T5" smd circle
			(at -1.196 2.917 180)
			(size 0.27 0.27)
			(layers "F.Cu" "F.Mask" "F.Paste")
			(net 36 "GND")
			(pinfunction "VSS")
			(pintype "passive")
		)
		(pad "T8" smd circle
			(at 1.205 2.917 180)
			(size 0.27 0.27)
			(layers "F.Cu" "F.Mask" "F.Paste")
			(net 36 "GND")
			(pinfunction "VSS")
			(pintype "passive")
		)
		(pad "T9" smd circle
			(at 2.004 2.917 180)
			(size 0.27 0.27)
			(layers "F.Cu" "F.Mask" "F.Paste")
			(net 187 "VDD1")
			(pinfunction "VDD1")
			(pintype "passive")
		)
		(pad "T10" smd circle
			(at 2.805 2.917 180)
			(size 0.27 0.27)
			(layers "F.Cu" "F.Mask" "F.Paste")
			(net 36 "GND")
			(pinfunction "VSS")
			(pintype "passive")
		)
		(pad "T11" smd circle
			(at 3.604 2.917 180)
			(size 0.27 0.27)
			(layers "F.Cu" "F.Mask" "F.Paste")
			(net 160 "Net-(U1A-RESET_N)")
			(pinfunction "RESET_N")
			(pintype "input")
		)
		(pad "T12" smd circle
			(at 4.405 2.917 180)
			(size 0.27 0.27)
			(layers "F.Cu" "F.Mask" "F.Paste")
			(net 36 "GND")
			(pinfunction "VSS")
			(pintype "passive")
		)
		(pad "U1" smd circle
			(at -4.396 3.567 180)
			(size 0.27 0.27)
			(layers "F.Cu" "F.Mask" "F.Paste")
			(net 187 "VDD1")
			(pinfunction "VDD1")
			(pintype "passive")
		)
		(pad "U2" smd circle
			(at -3.596 3.567 180)
			(size 0.27 0.27)
			(layers "F.Cu" "F.Mask" "F.Paste")
			(net 235 "unconnected-(U1B-DQ3_B-PadU2)")
			(pinfunction "DQ3_B")
			(pintype "bidirectional+no_connect")
		)
		(pad "U3" smd circle
			(at -2.795 3.567 180)
			(size 0.27 0.27)
			(layers "F.Cu" "F.Mask" "F.Paste")
			(net 189 "VDDQ")
			(pinfunction "VDDQ")
			(pintype "passive")
		)
		(pad "U4" smd circle
			(at -1.996 3.567 180)
			(size 0.27 0.27)
			(layers "F.Cu" "F.Mask" "F.Paste")
			(net 236 "unconnected-(U1B-DQ4_B-PadU4)")
			(pinfunction "DQ4_B")
			(pintype "bidirectional+no_connect")
		)
		(pad "U5" smd circle
			(at -1.196 3.567 180)
			(size 0.27 0.27)
			(layers "F.Cu" "F.Mask" "F.Paste")
			(net 188 "VDD2")
			(pinfunction "VDD2")
			(pintype "passive")
		)
		(pad "U8" smd circle
			(at 1.205 3.567 180)
			(size 0.27 0.27)
			(layers "F.Cu" "F.Mask" "F.Paste")
			(net 188 "VDD2")
			(pinfunction "VDD2")
			(pintype "passive")
		)
		(pad "U9" smd circle
			(at 2.004 3.567 180)
			(size 0.27 0.27)
			(layers "F.Cu" "F.Mask" "F.Paste")
			(net 237 "unconnected-(U1B-DQ12_B-PadU9)")
			(pinfunction "DQ12_B")
			(pintype "bidirectional+no_connect")
		)
		(pad "U10" smd circle
			(at 2.805 3.567 180)
			(size 0.27 0.27)
			(layers "F.Cu" "F.Mask" "F.Paste")
			(net 189 "VDDQ")
			(pinfunction "VDDQ")
			(pintype "passive")
		)
		(pad "U11" smd circle
			(at 3.604 3.567 180)
			(size 0.27 0.27)
			(layers "F.Cu" "F.Mask" "F.Paste")
			(net 238 "unconnected-(U1B-DQ11_B-PadU11)")
			(pinfunction "DQ11_B")
			(pintype "bidirectional+no_connect")
		)
		(pad "U12" smd circle
			(at 4.405 3.567 180)
			(size 0.27 0.27)
			(layers "F.Cu" "F.Mask" "F.Paste")
			(net 187 "VDD1")
			(pinfunction "VDD1")
			(pintype "passive")
		)
		(pad "V1" smd circle
			(at -4.396 4.217 180)
			(size 0.27 0.27)
			(layers "F.Cu" "F.Mask" "F.Paste")
			(net 36 "GND")
			(pinfunction "VSS")
			(pintype "passive")
		)
		(pad "V2" smd circle
			(at -3.596 4.217 180)
			(size 0.27 0.27)
			(layers "F.Cu" "F.Mask" "F.Paste")
			(net 239 "unconnected-(U1B-DQ2_B-PadV2)")
			(pinfunction "DQ2_B")
			(pintype "bidirectional+no_connect")
		)
		(pad "V3" smd circle
			(at -2.795 4.217 180)
			(size 0.27 0.27)
			(layers "F.Cu" "F.Mask" "F.Paste")
			(net 240 "unconnected-(U1B-DQS0_C_B-PadV3)")
			(pinfunction "DQS0_C_B")
			(pintype "bidirectional+no_connect")
		)
		(pad "V4" smd circle
			(at -1.996 4.217 180)
			(size 0.27 0.27)
			(layers "F.Cu" "F.Mask" "F.Paste")
			(net 242 "unconnected-(U1B-DQ5_B-PadV4)")
			(pinfunction "DQ5_B")
			(pintype "bidirectional+no_connect")
		)
		(pad "V5" smd circle
			(at -1.196 4.217 180)
			(size 0.27 0.27)
			(layers "F.Cu" "F.Mask" "F.Paste")
			(net 36 "GND")
			(pinfunction "VSS")
			(pintype "passive")
		)
		(pad "V8" smd circle
			(at 1.205 4.217 180)
			(size 0.27 0.27)
			(layers "F.Cu" "F.Mask" "F.Paste")
			(net 36 "GND")
			(pinfunction "VSS")
			(pintype "passive")
		)
		(pad "V9" smd circle
			(at 2.004 4.217 180)
			(size 0.27 0.27)
			(layers "F.Cu" "F.Mask" "F.Paste")
			(net 243 "unconnected-(U1B-DQ13_B-PadV9)")
			(pinfunction "DQ13_B")
			(pintype "bidirectional+no_connect")
		)
		(pad "V10" smd circle
			(at 2.805 4.217 180)
			(size 0.27 0.27)
			(layers "F.Cu" "F.Mask" "F.Paste")
			(net 244 "unconnected-(U1B-DQS1_C_B-PadV10)")
			(pinfunction "DQS1_C_B")
			(pintype "bidirectional+no_connect")
		)
		(pad "V11" smd circle
			(at 3.604 4.217 180)
			(size 0.27 0.27)
			(layers "F.Cu" "F.Mask" "F.Paste")
			(net 245 "unconnected-(U1B-DQ10_B-PadV11)")
			(pinfunction "DQ10_B")
			(pintype "bidirectional+no_connect")
		)
		(pad "V12" smd circle
			(at 4.405 4.217 180)
			(size 0.27 0.27)
			(layers "F.Cu" "F.Mask" "F.Paste")
			(net 36 "GND")
			(pinfunction "VSS")
			(pintype "passive")
		)
		(pad "W1" smd circle
			(at -4.396 4.866 180)
			(size 0.27 0.27)
			(layers "F.Cu" "F.Mask" "F.Paste")
			(net 189 "VDDQ")
			(pinfunction "VDDQ")
			(pintype "passive")
		)
		(pad "W2" smd circle
			(at -3.596 4.866 180)
			(size 0.27 0.27)
			(layers "F.Cu" "F.Mask" "F.Paste")
			(net 36 "GND")
			(pinfunction "VSS")
			(pintype "passive")
		)
		(pad "W3" smd circle
			(at -2.795 4.866 180)
			(size 0.27 0.27)
			(layers "F.Cu" "F.Mask" "F.Paste")
			(net 248 "unconnected-(U1B-DQS0_T_B-PadW3)")
			(pinfunction "DQS0_T_B")
			(pintype "bidirectional+no_connect")
		)
		(pad "W4" smd circle
			(at -1.996 4.866 180)
			(size 0.27 0.27)
			(layers "F.Cu" "F.Mask" "F.Paste")
			(net 36 "GND")
			(pinfunction "VSS")
			(pintype "passive")
		)
		(pad "W5" smd circle
			(at -1.196 4.866 180)
			(size 0.27 0.27)
			(layers "F.Cu" "F.Mask" "F.Paste")
			(net 189 "VDDQ")
			(pinfunction "VDDQ")
			(pintype "passive")
		)
		(pad "W8" smd circle
			(at 1.205 4.866 180)
			(size 0.27 0.27)
			(layers "F.Cu" "F.Mask" "F.Paste")
			(net 189 "VDDQ")
			(pinfunction "VDDQ")
			(pintype "passive")
		)
		(pad "W9" smd circle
			(at 2.004 4.866 180)
			(size 0.27 0.27)
			(layers "F.Cu" "F.Mask" "F.Paste")
			(net 36 "GND")
			(pinfunction "VSS")
			(pintype "passive")
		)
		(pad "W10" smd circle
			(at 2.805 4.866 180)
			(size 0.27 0.27)
			(layers "F.Cu" "F.Mask" "F.Paste")
			(net 249 "unconnected-(U1B-DQS1_T_B-PadW10)")
			(pinfunction "DQS1_T_B")
			(pintype "bidirectional+no_connect")
		)
		(pad "W11" smd circle
			(at 3.604 4.866 180)
			(size 0.27 0.27)
			(layers "F.Cu" "F.Mask" "F.Paste")
			(net 36 "GND")
			(pinfunction "VSS")
			(pintype "passive")
		)
		(pad "W12" smd circle
			(at 4.405 4.866 180)
			(size 0.27 0.27)
			(layers "F.Cu" "F.Mask" "F.Paste")
			(net 189 "VDDQ")
			(pinfunction "VDDQ")
			(pintype "passive")
		)
		(pad "Y1" smd circle
			(at -4.396 5.517 180)
			(size 0.27 0.27)
			(layers "F.Cu" "F.Mask" "F.Paste")
			(net 36 "GND")
			(pinfunction "VSS")
			(pintype "passive")
		)
		(pad "Y2" smd circle
			(at -3.596 5.517 180)
			(size 0.27 0.27)
			(layers "F.Cu" "F.Mask" "F.Paste")
			(net 250 "unconnected-(U1B-DQ1_B-PadY2)")
			(pinfunction "DQ1_B")
			(pintype "bidirectional+no_connect")
		)
		(pad "Y3" smd circle
			(at -2.795 5.517 180)
			(size 0.27 0.27)
			(layers "F.Cu" "F.Mask" "F.Paste")
			(net 251 "unconnected-(U1B-DMI0_B-PadY3)")
			(pinfunction "DMI0_B")
			(pintype "bidirectional+no_connect")
		)
		(pad "Y4" smd circle
			(at -1.996 5.517 180)
			(size 0.27 0.27)
			(layers "F.Cu" "F.Mask" "F.Paste")
			(net 252 "unconnected-(U1B-DQ6_B-PadY4)")
			(pinfunction "DQ6_B")
			(pintype "bidirectional+no_connect")
		)
		(pad "Y5" smd circle
			(at -1.196 5.517 180)
			(size 0.27 0.27)
			(layers "F.Cu" "F.Mask" "F.Paste")
			(net 36 "GND")
			(pinfunction "VSS")
			(pintype "passive")
		)
		(pad "Y8" smd circle
			(at 1.205 5.517 180)
			(size 0.27 0.27)
			(layers "F.Cu" "F.Mask" "F.Paste")
			(net 36 "GND")
			(pinfunction "VSS")
			(pintype "passive")
		)
		(pad "Y9" smd circle
			(at 2.004 5.517 180)
			(size 0.27 0.27)
			(layers "F.Cu" "F.Mask" "F.Paste")
			(net 253 "unconnected-(U1B-DQ14_B-PadY9)")
			(pinfunction "DQ14_B")
			(pintype "bidirectional+no_connect")
		)
		(pad "Y10" smd circle
			(at 2.805 5.517 180)
			(size 0.27 0.27)
			(layers "F.Cu" "F.Mask" "F.Paste")
			(net 254 "unconnected-(U1B-DMI1_B-PadY10)")
			(pinfunction "DMI1_B")
			(pintype "bidirectional+no_connect")
		)
		(pad "Y11" smd circle
			(at 3.604 5.517 180)
			(size 0.27 0.27)
			(layers "F.Cu" "F.Mask" "F.Paste")
			(net 259 "unconnected-(U1B-DQ9_B-PadY11)")
			(pinfunction "DQ9_B")
			(pintype "bidirectional+no_connect")
		)
		(pad "Y12" smd circle
			(at 4.405 5.517 180)
			(size 0.27 0.27)
			(layers "F.Cu" "F.Mask" "F.Paste")
			(net 36 "GND")
			(pinfunction "VSS")
			(pintype "passive")
		)
	)
	(footprint "antmicro-footprints:R_0402_1005Metric"
		(layer "F.Cu")
		(at 158.375 88.55 180)
		(descr "Resistor SMD 0402")
		(tags "resistor SMD 0402")
		(property "Reference" "R1"
			(at -2.45 -0.35 0)
			(layer "F.SilkS")
			(effects
				(font
					(size 0.7 0.7)
					(thickness 0.15)
				)
				(justify right bottom)
			)
		)
		(property "Value" "R_10k_0402"
			(at 0 1.4 0)
			(layer "F.Fab")
			(effects
				(font
					(size 0.7 0.7)
					(thickness 0.15)
				)
				(justify right bottom)
			)
		)
		(property "Description" "10k resistor in 0402 package with 1% tolerance"
			(at 0 0 180)
			(layer "F.Fab")
			(hide yes)
			(effects
				(font
					(size 1.27 1.27)
					(thickness 0.15)
				)
			)
		)
		(property "Author" "Antmicro"
			(at 316.75 177.1 0)
			(layer "F.Fab")
			(hide yes)
			(effects
				(font
					(size 1 1)
					(thickness 0.15)
				)
			)
		)
		(property "License" "Apache-2.0"
			(at 316.75 177.1 0)
			(layer "F.Fab")
			(hide yes)
			(effects
				(font
					(size 1 1)
					(thickness 0.15)
				)
			)
		)
		(property "MPN" "CRCW040210K0FKEDHP"
			(at 316.75 177.1 0)
			(layer "F.Fab")
			(hide yes)
			(effects
				(font
					(size 1 1)
					(thickness 0.15)
				)
			)
		)
		(property "Manufacturer" "VISHAY"
			(at 316.75 177.1 0)
			(layer "F.Fab")
			(hide yes)
			(effects
				(font
					(size 1 1)
					(thickness 0.15)
				)
			)
		)
		(property "Tolerance" "1%"
			(at 316.75 177.1 0)
			(layer "F.Fab")
			(hide yes)
			(effects
				(font
					(size 1 1)
					(thickness 0.15)
				)
			)
		)
		(property "Val" "10k"
			(at 316.75 177.1 0)
			(layer "F.Fab")
			(hide yes)
			(effects
				(font
					(size 1 1)
					(thickness 0.15)
				)
			)
		)
		(sheetname "LPDDR4")
		(sheetfile "lpddr4.kicad_sch")
		(attr smd)
		(fp_rect
			(start -0.93 -0.47)
			(end 0.93 0.47)
			(stroke
				(width 0.05)
				(type solid)
			)
			(fill no)
			(layer "F.CrtYd")
		)
		(fp_rect
			(start -0.5 -0.25)
			(end 0.5 0.25)
			(stroke
				(width 0.15)
				(type solid)
			)
			(fill no)
			(layer "F.Fab")
		)
		(pad "1" smd roundrect
			(at -0.485 0 180)
			(size 0.59 0.64)
			(layers "F.Cu" "F.Mask" "F.Paste")
			(roundrect_rratio 0.25)
			(net 189 "VDDQ")
			(pintype "passive")
		)
		(pad "2" smd roundrect
			(at 0.485 0 180)
			(size 0.59 0.64)
			(layers "F.Cu" "F.Mask" "F.Paste")
			(roundrect_rratio 0.25)
			(net 158 "Net-(U1A-ODT_CA_A)")
			(pintype "passive")
		)
	)
	(footprint "antmicro-footprints:C_0201"
		(layer "F.Cu")
		(at 155.855 93.2 -90)
		(descr "Capacitor SMD 0201")
		(tags "capacitor SMD 0201")
		(property "Reference" "C1"
			(at -0.15 -1.22 90)
			(layer "F.SilkS")
			(effects
				(font
					(size 0.7 0.7)
					(thickness 0.15)
				)
				(justify right bottom)
			)
		)
		(property "Value" "C_100n_0201"
			(at 0 1.4 90)
			(layer "F.Fab")
			(effects
				(font
					(size 0.7 0.7)
					(thickness 0.15)
				)
				(justify right bottom)
			)
		)
		(property "Description" " "
			(at 0 0 270)
			(layer "F.Fab")
			(hide yes)
			(effects
				(font
					(size 1.27 1.27)
					(thickness 0.15)
				)
			)
		)
		(property "Author" "Antmicro"
			(at 62.655 249.055 0)
			(layer "F.Fab")
			(hide yes)
			(effects
				(font
					(size 1 1)
					(thickness 0.15)
				)
			)
		)
		(property "Dielectric" ""
			(at 62.655 249.055 0)
			(layer "F.Fab")
			(hide yes)
			(effects
				(font
					(size 1 1)
					(thickness 0.15)
				)
			)
		)
		(property "License" "Apache-2.0"
			(at 62.655 249.055 0)
			(layer "F.Fab")
			(hide yes)
			(effects
				(font
					(size 1 1)
					(thickness 0.15)
				)
			)
		)
		(property "MPN" "CC0201KRX6S5BB104"
			(at 62.655 249.055 0)
			(layer "F.Fab")
			(hide yes)
			(effects
				(font
					(size 1 1)
					(thickness 0.15)
				)
			)
		)
		(property "Manufacturer" "YAGEO"
			(at 62.655 249.055 0)
			(layer "F.Fab")
			(hide yes)
			(effects
				(font
					(size 1 1)
					(thickness 0.15)
				)
			)
		)
		(property "Val" "100n"
			(at 62.655 249.055 0)
			(layer "F.Fab")
			(hide yes)
			(effects
				(font
					(size 1 1)
					(thickness 0.15)
				)
			)
		)
		(property "Voltage" ""
			(at 62.655 249.055 0)
			(layer "F.Fab")
			(hide yes)
			(effects
				(font
					(size 1 1)
					(thickness 0.15)
				)
			)
		)
		(sheetname "LPDDR4")
		(sheetfile "lpddr4.kicad_sch")
		(attr smd)
		(fp_rect
			(start -0.72 -0.38)
			(end 0.72 0.38)
			(stroke
				(width 0.05)
				(type solid)
			)
			(fill no)
			(layer "F.CrtYd")
		)
		(fp_rect
			(start 0.3 0.15)
			(end -0.301 -0.149)
			(stroke
				(width 0.15)
				(type solid)
			)
			(fill no)
			(layer "F.Fab")
		)
		(pad "" smd roundrect
			(at -0.349 -0.002 270)
			(size 0.318 0.36)
			(layers "F.Paste")
			(roundrect_rratio 0.25)
		)
		(pad "" smd roundrect
			(at 0.341 -0.002 270)
			(size 0.318 0.36)
			(layers "F.Paste")
			(roundrect_rratio 0.25)
		)
		(pad "1" smd roundrect
			(at -0.321 -0.002 270)
			(size 0.46 0.4)
			(layers "F.Cu" "F.Mask")
			(roundrect_rratio 0.25)
			(net 36 "GND")
			(pintype "passive")
		)
		(pad "2" smd roundrect
			(at 0.32 -0.002 270)
			(size 0.46 0.4)
			(layers "F.Cu" "F.Mask")
			(roundrect_rratio 0.25)
			(net 189 "VDDQ")
			(pintype "passive")
		)
	)
	(footprint "antmicro-footprints:R_0402_1005Metric"
		(layer "F.Cu")
		(at 158.375 83.6 180)
		(descr "Resistor SMD 0402")
		(tags "resistor SMD 0402")
		(property "Reference" "R4"
			(at -0.8 -0.45 180)
			(layer "F.SilkS")
			(effects
				(font
					(size 0.7 0.7)
					(thickness 0.15)
				)
				(justify left bottom)
			)
		)
		(property "Value" "R_10k_0402"
			(at 0 1.4 180)
			(layer "F.Fab")
			(effects
				(font
					(size 0.7 0.7)
					(thickness 0.15)
				)
				(justify left bottom)
			)
		)
		(property "Description" "10k resistor in 0402 package with 1% tolerance"
			(at 0 0 180)
			(layer "F.Fab")
			(hide yes)
			(effects
				(font
					(size 1.27 1.27)
					(thickness 0.15)
				)
			)
		)
		(property "Author" "Antmicro"
			(at 316.75 167.2 0)
			(layer "F.Fab")
			(hide yes)
			(effects
				(font
					(size 1 1)
					(thickness 0.15)
				)
			)
		)
		(property "License" "Apache-2.0"
			(at 316.75 167.2 0)
			(layer "F.Fab")
			(hide yes)
			(effects
				(font
					(size 1 1)
					(thickness 0.15)
				)
			)
		)
		(property "MPN" "CRCW040210K0FKEDHP"
			(at 316.75 167.2 0)
			(layer "F.Fab")
			(hide yes)
			(effects
				(font
					(size 1 1)
					(thickness 0.15)
				)
			)
		)
		(property "Manufacturer" "VISHAY"
			(at 316.75 167.2 0)
			(layer "F.Fab")
			(hide yes)
			(effects
				(font
					(size 1 1)
					(thickness 0.15)
				)
			)
		)
		(property "Tolerance" "1%"
			(at 316.75 167.2 0)
			(layer "F.Fab")
			(hide yes)
			(effects
				(font
					(size 1 1)
					(thickness 0.15)
				)
			)
		)
		(property "Val" "10k"
			(at 316.75 167.2 0)
			(layer "F.Fab")
			(hide yes)
			(effects
				(font
					(size 1 1)
					(thickness 0.15)
				)
			)
		)
		(sheetname "LPDDR4")
		(sheetfile "lpddr4.kicad_sch")
		(attr smd)
		(fp_rect
			(start -0.93 -0.47)
			(end 0.93 0.47)
			(stroke
				(width 0.05)
				(type solid)
			)
			(fill no)
			(layer "F.CrtYd")
		)
		(fp_rect
			(start -0.5 -0.25)
			(end 0.5 0.25)
			(stroke
				(width 0.15)
				(type solid)
			)
			(fill no)
			(layer "F.Fab")
		)
		(pad "1" smd roundrect
			(at -0.485 0 180)
			(size 0.59 0.64)
			(layers "F.Cu" "F.Mask" "F.Paste")
			(roundrect_rratio 0.25)
			(net 189 "VDDQ")
			(pintype "passive")
		)
		(pad "2" smd roundrect
			(at 0.485 0 180)
			(size 0.59 0.64)
			(layers "F.Cu" "F.Mask" "F.Paste")
			(roundrect_rratio 0.25)
			(net 159 "Net-(U1B-ODT_CA_B)")
			(pintype "passive")
		)
	)
	(footprint "antmicro-footprints:R_0402_1005Metric"
		(layer "F.Cu")
		(at 140.725 83.95 -90)
		(descr "Resistor SMD 0402")
		(tags "resistor SMD 0402")
		(property "Reference" "R5"
			(at -0.8 0.55 90)
			(layer "F.SilkS")
			(effects
				(font
					(size 0.7 0.7)
					(thickness 0.15)
				)
				(justify right bottom)
			)
		)
		(property "Value" "R_10k_0402"
			(at 0 1.4 90)
			(layer "F.Fab")
			(effects
				(font
					(size 0.7 0.7)
					(thickness 0.15)
				)
				(justify right bottom)
			)
		)
		(property "Description" "10k resistor in 0402 package with 1% tolerance"
			(at 0 0 270)
			(layer "F.Fab")
			(hide yes)
			(effects
				(font
					(size 1.27 1.27)
					(thickness 0.15)
				)
			)
		)
		(property "Author" "Antmicro"
			(at 56.775 224.675 0)
			(layer "F.Fab")
			(hide yes)
			(effects
				(font
					(size 1 1)
					(thickness 0.15)
				)
			)
		)
		(property "License" "Apache-2.0"
			(at 56.775 224.675 0)
			(layer "F.Fab")
			(hide yes)
			(effects
				(font
					(size 1 1)
					(thickness 0.15)
				)
			)
		)
		(property "MPN" "CRCW040210K0FKEDHP"
			(at 56.775 224.675 0)
			(layer "F.Fab")
			(hide yes)
			(effects
				(font
					(size 1 1)
					(thickness 0.15)
				)
			)
		)
		(property "Manufacturer" "VISHAY"
			(at 56.775 224.675 0)
			(layer "F.Fab")
			(hide yes)
			(effects
				(font
					(size 1 1)
					(thickness 0.15)
				)
			)
		)
		(property "Tolerance" "1%"
			(at 56.775 224.675 0)
			(layer "F.Fab")
			(hide yes)
			(effects
				(font
					(size 1 1)
					(thickness 0.15)
				)
			)
		)
		(property "Val" "10k"
			(at 56.775 224.675 0)
			(layer "F.Fab")
			(hide yes)
			(effects
				(font
					(size 1 1)
					(thickness 0.15)
				)
			)
		)
		(sheetname "LPDDR4")
		(sheetfile "lpddr4.kicad_sch")
		(attr smd)
		(fp_rect
			(start -0.93 -0.47)
			(end 0.93 0.47)
			(stroke
				(width 0.05)
				(type solid)
			)
			(fill no)
			(layer "F.CrtYd")
		)
		(fp_rect
			(start -0.5 -0.25)
			(end 0.5 0.25)
			(stroke
				(width 0.15)
				(type solid)
			)
			(fill no)
			(layer "F.Fab")
		)
		(pad "1" smd roundrect
			(at -0.485 0 270)
			(size 0.59 0.64)
			(layers "F.Cu" "F.Mask" "F.Paste")
			(roundrect_rratio 0.25)
			(net 189 "VDDQ")
			(pintype "passive")
		)
		(pad "2" smd roundrect
			(at 0.485 0 270)
			(size 0.59 0.64)
			(layers "F.Cu" "F.Mask" "F.Paste")
			(roundrect_rratio 0.25)
			(net 160 "Net-(U1A-RESET_N)")
			(pintype "passive")
		)
	)
	(footprint "antmicro-footprints:R_0402_1005Metric"
		(layer "F.Cu")
		(at 141.175 85.9)
		(descr "Resistor SMD 0402")
		(tags "resistor SMD 0402")
		(property "Reference" "R7"
			(at -2.4 0.35 0)
			(layer "F.SilkS")
			(effects
				(font
					(size 0.7 0.7)
					(thickness 0.15)
				)
				(justify left bottom)
			)
		)
		(property "Value" "R_0R_0402"
			(at 0 1.4 0)
			(layer "F.Fab")
			(effects
				(font
					(size 0.7 0.7)
					(thickness 0.15)
				)
				(justify left bottom)
			)
		)
		(property "Description" "0R resistor in 0402 package with unspecified tolerance"
			(at 0 0 0)
			(layer "F.Fab")
			(hide yes)
			(effects
				(font
					(size 1.27 1.27)
					(thickness 0.15)
				)
			)
		)
		(property "Author" "Antmicro"
			(at 0 0 0)
			(layer "F.Fab")
			(hide yes)
			(effects
				(font
					(size 1 1)
					(thickness 0.15)
				)
			)
		)
		(property "Current" "1A"
			(at 0 0 0)
			(layer "F.Fab")
			(hide yes)
			(effects
				(font
					(size 1 1)
					(thickness 0.15)
				)
			)
		)
		(property "License" "Apache-2.0"
			(at 0 0 0)
			(layer "F.Fab")
			(hide yes)
			(effects
				(font
					(size 1 1)
					(thickness 0.15)
				)
			)
		)
		(property "MPN" "ERJ2GE0R00X"
			(at 0 0 0)
			(layer "F.Fab")
			(hide yes)
			(effects
				(font
					(size 1 1)
					(thickness 0.15)
				)
			)
		)
		(property "Manufacturer" "PANASONIC"
			(at 0 0 0)
			(layer "F.Fab")
			(hide yes)
			(effects
				(font
					(size 1 1)
					(thickness 0.15)
				)
			)
		)
		(property "Tolerance" ""
			(at 0 0 0)
			(layer "F.Fab")
			(hide yes)
			(effects
				(font
					(size 1 1)
					(thickness 0.15)
				)
			)
		)
		(property "Val" "0R"
			(at 0 0 0)
			(layer "F.Fab")
			(hide yes)
			(effects
				(font
					(size 1 1)
					(thickness 0.15)
				)
			)
		)
		(sheetname "LPDDR4")
		(sheetfile "lpddr4.kicad_sch")
		(attr smd)
		(fp_rect
			(start -0.93 -0.47)
			(end 0.93 0.47)
			(stroke
				(width 0.05)
				(type solid)
			)
			(fill no)
			(layer "F.CrtYd")
		)
		(fp_rect
			(start -0.5 -0.25)
			(end 0.5 0.25)
			(stroke
				(width 0.15)
				(type solid)
			)
			(fill no)
			(layer "F.Fab")
		)
		(pad "1" smd roundrect
			(at -0.485 0)
			(size 0.59 0.64)
			(layers "F.Cu" "F.Mask" "F.Paste")
			(roundrect_rratio 0.25)
			(net 160 "Net-(U1A-RESET_N)")
			(pintype "passive")
		)
		(pad "2" smd roundrect
			(at 0.485 0)
			(size 0.59 0.64)
			(layers "F.Cu" "F.Mask" "F.Paste")
			(roundrect_rratio 0.25)
			(net 230 "RESET_N")
			(pintype "passive")
		)
	)
	(footprint "antmicro-footprints:R_0402_1005Metric"
		(layer "F.Cu")
		(at 150.416 94.969)
		(descr "Resistor SMD 0402")
		(tags "resistor SMD 0402")
		(property "Reference" "R6"
			(at -1.041 -0.519 0)
			(layer "F.SilkS")
			(effects
				(font
					(size 0.7 0.7)
					(thickness 0.15)
				)
				(justify left bottom)
			)
		)
		(property "Value" "R_240R_0402"
			(at 0 1.4 0)
			(layer "F.Fab")
			(effects
				(font
					(size 0.7 0.7)
					(thickness 0.15)
				)
				(justify left bottom)
			)
		)
		(property "Description" "240R resistor in 0402 package with 1% tolerance"
			(at 0 0 0)
			(layer "F.Fab")
			(hide yes)
			(effects
				(font
					(size 1.27 1.27)
					(thickness 0.15)
				)
			)
		)
		(property "Author" "Antmicro"
			(at 0 0 0)
			(layer "F.Fab")
			(hide yes)
			(effects
				(font
					(size 1 1)
					(thickness 0.15)
				)
			)
		)
		(property "License" "Apache-2.0"
			(at 0 0 0)
			(layer "F.Fab")
			(hide yes)
			(effects
				(font
					(size 1 1)
					(thickness 0.15)
				)
			)
		)
		(property "MPN" "ERJ2GEJ241X"
			(at 0 0 0)
			(layer "F.Fab")
			(hide yes)
			(effects
				(font
					(size 1 1)
					(thickness 0.15)
				)
			)
		)
		(property "Manufacturer" "PANASONIC"
			(at 0 0 0)
			(layer "F.Fab")
			(hide yes)
			(effects
				(font
					(size 1 1)
					(thickness 0.15)
				)
			)
		)
		(property "Tolerance" "1%"
			(at 0 0 0)
			(layer "F.Fab")
			(hide yes)
			(effects
				(font
					(size 1 1)
					(thickness 0.15)
				)
			)
		)
		(property "Val" "240R"
			(at 0 0 0)
			(layer "F.Fab")
			(hide yes)
			(effects
				(font
					(size 1 1)
					(thickness 0.15)
				)
			)
		)
		(sheetname "LPDDR4")
		(sheetfile "lpddr4.kicad_sch")
		(attr smd)
		(fp_rect
			(start -0.93 -0.47)
			(end 0.93 0.47)
			(stroke
				(width 0.05)
				(type solid)
			)
			(fill no)
			(layer "F.CrtYd")
		)
		(fp_rect
			(start -0.5 -0.25)
			(end 0.5 0.25)
			(stroke
				(width 0.15)
				(type solid)
			)
			(fill no)
			(layer "F.Fab")
		)
		(pad "1" smd roundrect
			(at -0.485 0)
			(size 0.59 0.64)
			(layers "F.Cu" "F.Mask" "F.Paste")
			(roundrect_rratio 0.25)
			(net 161 "Net-(U1A-ZQ0)")
			(pintype "passive")
		)
		(pad "2" smd roundrect
			(at 0.485 0)
			(size 0.59 0.64)
			(layers "F.Cu" "F.Mask" "F.Paste")
			(roundrect_rratio 0.25)
			(net 36 "GND")
			(pintype "passive")
		)
	)
	(footprint "antmicro-footprints:C_0201"
		(layer "F.Cu")
		(at 142.925 82.75 90)
		(descr "Capacitor SMD 0201")
		(tags "capacitor SMD 0201")
		(property "Reference" "C24"
			(at -0.6 -0.55 90)
			(layer "F.SilkS")
			(effects
				(font
					(size 0.7 0.7)
					(thickness 0.15)
				)
				(justify left bottom)
			)
		)
		(property "Value" "C_100n_0201"
			(at 0 1.4 90)
			(layer "F.Fab")
			(effects
				(font
					(size 0.7 0.7)
					(thickness 0.15)
				)
				(justify left bottom)
			)
		)
		(property "Description" " "
			(at 0 0 90)
			(layer "F.Fab")
			(hide yes)
			(effects
				(font
					(size 1.27 1.27)
					(thickness 0.15)
				)
			)
		)
		(property "Author" "Antmicro"
			(at 225.675 -60.175 0)
			(layer "F.Fab")
			(hide yes)
			(effects
				(font
					(size 1 1)
					(thickness 0.15)
				)
			)
		)
		(property "Dielectric" ""
			(at 225.675 -60.175 0)
			(layer "F.Fab")
			(hide yes)
			(effects
				(font
					(size 1 1)
					(thickness 0.15)
				)
			)
		)
		(property "License" "Apache-2.0"
			(at 225.675 -60.175 0)
			(layer "F.Fab")
			(hide yes)
			(effects
				(font
					(size 1 1)
					(thickness 0.15)
				)
			)
		)
		(property "MPN" "CC0201KRX6S5BB104"
			(at 225.675 -60.175 0)
			(layer "F.Fab")
			(hide yes)
			(effects
				(font
					(size 1 1)
					(thickness 0.15)
				)
			)
		)
		(property "Manufacturer" "YAGEO"
			(at 225.675 -60.175 0)
			(layer "F.Fab")
			(hide yes)
			(effects
				(font
					(size 1 1)
					(thickness 0.15)
				)
			)
		)
		(property "Val" "100n"
			(at 225.675 -60.175 0)
			(layer "F.Fab")
			(hide yes)
			(effects
				(font
					(size 1 1)
					(thickness 0.15)
				)
			)
		)
		(property "Voltage" ""
			(at 225.675 -60.175 0)
			(layer "F.Fab")
			(hide yes)
			(effects
				(font
					(size 1 1)
					(thickness 0.15)
				)
			)
		)
		(sheetname "LPDDR4")
		(sheetfile "lpddr4.kicad_sch")
		(attr smd)
		(fp_rect
			(start -0.72 -0.38)
			(end 0.72 0.38)
			(stroke
				(width 0.05)
				(type solid)
			)
			(fill no)
			(layer "F.CrtYd")
		)
		(fp_rect
			(start 0.3 0.15)
			(end -0.301 -0.149)
			(stroke
				(width 0.15)
				(type solid)
			)
			(fill no)
			(layer "F.Fab")
		)
		(pad "" smd roundrect
			(at -0.349 -0.002 90)
			(size 0.318 0.36)
			(layers "F.Paste")
			(roundrect_rratio 0.25)
		)
		(pad "" smd roundrect
			(at 0.341 -0.002 90)
			(size 0.318 0.36)
			(layers "F.Paste")
			(roundrect_rratio 0.25)
		)
		(pad "1" smd roundrect
			(at -0.321 -0.002 90)
			(size 0.46 0.4)
			(layers "F.Cu" "F.Mask")
			(roundrect_rratio 0.25)
			(net 36 "GND")
			(pintype "passive")
		)
		(pad "2" smd roundrect
			(at 0.32 -0.002 90)
			(size 0.46 0.4)
			(layers "F.Cu" "F.Mask")
			(roundrect_rratio 0.25)
			(net 187 "VDD1")
			(pintype "passive")
		)
	)
	(footprint "antmicro-footprints:C_0201"
		(layer "F.Cu")
		(at 142.925 81.25 90)
		(descr "Capacitor SMD 0201")
		(tags "capacitor SMD 0201")
		(property "Reference" "C10"
			(at 0.2 -0.55 90)
			(layer "F.SilkS")
			(effects
				(font
					(size 0.7 0.7)
					(thickness 0.15)
				)
				(justify left bottom)
			)
		)
		(property "Value" "C_100n_0201"
			(at 0 1.4 90)
			(layer "F.Fab")
			(effects
				(font
					(size 0.7 0.7)
					(thickness 0.15)
				)
				(justify left bottom)
			)
		)
		(property "Description" " "
			(at 0 0 90)
			(layer "F.Fab")
			(hide yes)
			(effects
				(font
					(size 1.27 1.27)
					(thickness 0.15)
				)
			)
		)
		(property "Author" "Antmicro"
			(at 224.175 -61.675 0)
			(layer "F.Fab")
			(hide yes)
			(effects
				(font
					(size 1 1)
					(thickness 0.15)
				)
			)
		)
		(property "Dielectric" ""
			(at 224.175 -61.675 0)
			(layer "F.Fab")
			(hide yes)
			(effects
				(font
					(size 1 1)
					(thickness 0.15)
				)
			)
		)
		(property "License" "Apache-2.0"
			(at 224.175 -61.675 0)
			(layer "F.Fab")
			(hide yes)
			(effects
				(font
					(size 1 1)
					(thickness 0.15)
				)
			)
		)
		(property "MPN" "CC0201KRX6S5BB104"
			(at 224.175 -61.675 0)
			(layer "F.Fab")
			(hide yes)
			(effects
				(font
					(size 1 1)
					(thickness 0.15)
				)
			)
		)
		(property "Manufacturer" "YAGEO"
			(at 224.175 -61.675 0)
			(layer "F.Fab")
			(hide yes)
			(effects
				(font
					(size 1 1)
					(thickness 0.15)
				)
			)
		)
		(property "Val" "100n"
			(at 224.175 -61.675 0)
			(layer "F.Fab")
			(hide yes)
			(effects
				(font
					(size 1 1)
					(thickness 0.15)
				)
			)
		)
		(property "Voltage" ""
			(at 224.175 -61.675 0)
			(layer "F.Fab")
			(hide yes)
			(effects
				(font
					(size 1 1)
					(thickness 0.15)
				)
			)
		)
		(sheetname "LPDDR4")
		(sheetfile "lpddr4.kicad_sch")
		(attr smd)
		(fp_rect
			(start -0.72 -0.38)
			(end 0.72 0.38)
			(stroke
				(width 0.05)
				(type solid)
			)
			(fill no)
			(layer "F.CrtYd")
		)
		(fp_rect
			(start 0.3 0.15)
			(end -0.301 -0.149)
			(stroke
				(width 0.15)
				(type solid)
			)
			(fill no)
			(layer "F.Fab")
		)
		(pad "" smd roundrect
			(at -0.349 -0.002 90)
			(size 0.318 0.36)
			(layers "F.Paste")
			(roundrect_rratio 0.25)
		)
		(pad "" smd roundrect
			(at 0.341 -0.002 90)
			(size 0.318 0.36)
			(layers "F.Paste")
			(roundrect_rratio 0.25)
		)
		(pad "1" smd roundrect
			(at -0.321 -0.002 90)
			(size 0.46 0.4)
			(layers "F.Cu" "F.Mask")
			(roundrect_rratio 0.25)
			(net 36 "GND")
			(pintype "passive")
		)
		(pad "2" smd roundrect
			(at 0.32 -0.002 90)
			(size 0.46 0.4)
			(layers "F.Cu" "F.Mask")
			(roundrect_rratio 0.25)
			(net 189 "VDDQ")
			(pintype "passive")
		)
	)
	(footprint "antmicro-footprints:C_0201"
		(layer "F.Cu")
		(at 142.925 84.25 90)
		(descr "Capacitor SMD 0201")
		(tags "capacitor SMD 0201")
		(property "Reference" "C15"
			(at -1.4 -0.45 90)
			(layer "F.SilkS")
			(effects
				(font
					(size 0.7 0.7)
					(thickness 0.15)
				)
				(justify left bottom)
			)
		)
		(property "Value" "C_100n_0201"
			(at 0 1.4 90)
			(layer "F.Fab")
			(effects
				(font
					(size 0.7 0.7)
					(thickness 0.15)
				)
				(justify left bottom)
			)
		)
		(property "Description" " "
			(at 0 0 90)
			(layer "F.Fab")
			(hide yes)
			(effects
				(font
					(size 1.27 1.27)
					(thickness 0.15)
				)
			)
		)
		(property "Author" "Antmicro"
			(at 227.175 -58.675 0)
			(layer "F.Fab")
			(hide yes)
			(effects
				(font
					(size 1 1)
					(thickness 0.15)
				)
			)
		)
		(property "Dielectric" ""
			(at 227.175 -58.675 0)
			(layer "F.Fab")
			(hide yes)
			(effects
				(font
					(size 1 1)
					(thickness 0.15)
				)
			)
		)
		(property "License" "Apache-2.0"
			(at 227.175 -58.675 0)
			(layer "F.Fab")
			(hide yes)
			(effects
				(font
					(size 1 1)
					(thickness 0.15)
				)
			)
		)
		(property "MPN" "CC0201KRX6S5BB104"
			(at 227.175 -58.675 0)
			(layer "F.Fab")
			(hide yes)
			(effects
				(font
					(size 1 1)
					(thickness 0.15)
				)
			)
		)
		(property "Manufacturer" "YAGEO"
			(at 227.175 -58.675 0)
			(layer "F.Fab")
			(hide yes)
			(effects
				(font
					(size 1 1)
					(thickness 0.15)
				)
			)
		)
		(property "Val" "100n"
			(at 227.175 -58.675 0)
			(layer "F.Fab")
			(hide yes)
			(effects
				(font
					(size 1 1)
					(thickness 0.15)
				)
			)
		)
		(property "Voltage" ""
			(at 227.175 -58.675 0)
			(layer "F.Fab")
			(hide yes)
			(effects
				(font
					(size 1 1)
					(thickness 0.15)
				)
			)
		)
		(sheetname "LPDDR4")
		(sheetfile "lpddr4.kicad_sch")
		(attr smd)
		(fp_rect
			(start -0.72 -0.38)
			(end 0.72 0.38)
			(stroke
				(width 0.05)
				(type solid)
			)
			(fill no)
			(layer "F.CrtYd")
		)
		(fp_rect
			(start 0.3 0.15)
			(end -0.301 -0.149)
			(stroke
				(width 0.15)
				(type solid)
			)
			(fill no)
			(layer "F.Fab")
		)
		(pad "" smd roundrect
			(at -0.349 -0.002 90)
			(size 0.318 0.36)
			(layers "F.Paste")
			(roundrect_rratio 0.25)
		)
		(pad "" smd roundrect
			(at 0.341 -0.002 90)
			(size 0.318 0.36)
			(layers "F.Paste")
			(roundrect_rratio 0.25)
		)
		(pad "1" smd roundrect
			(at -0.321 -0.002 90)
			(size 0.46 0.4)
			(layers "F.Cu" "F.Mask")
			(roundrect_rratio 0.25)
			(net 36 "GND")
			(pintype "passive")
		)
		(pad "2" smd roundrect
			(at 0.32 -0.002 90)
			(size 0.46 0.4)
			(layers "F.Cu" "F.Mask")
			(roundrect_rratio 0.25)
			(net 188 "VDD2")
			(pintype "passive")
		)
	)
	(footprint "antmicro-footprints:C_0402_1005Metric"
		(layer "F.Cu")
		(at 134.175 85.2 -90)
		(descr "Capacitor SMD 0402")
		(tags "capacitor SMD 0402")
		(property "Reference" "C34"
			(at -1.05 -1.4 90)
			(layer "F.SilkS")
			(effects
				(font
					(size 0.7 0.7)
					(thickness 0.15)
				)
				(justify right bottom)
			)
		)
		(property "Value" "C_4u7_0402"
			(at 0 1.4 90)
			(layer "F.Fab")
			(effects
				(font
					(size 0.7 0.7)
					(thickness 0.15)
				)
				(justify right bottom)
			)
		)
		(property "Description" " "
			(at 0 0 270)
			(layer "F.Fab")
			(hide yes)
			(effects
				(font
					(size 1.27 1.27)
					(thickness 0.15)
				)
			)
		)
		(property "Author" "Antmicro"
			(at 48.975 219.375 0)
			(layer "F.Fab")
			(hide yes)
			(effects
				(font
					(size 1 1)
					(thickness 0.15)
				)
			)
		)
		(property "Dielectric" ""
			(at 48.975 219.375 0)
			(layer "F.Fab")
			(hide yes)
			(effects
				(font
					(size 1 1)
					(thickness 0.15)
				)
			)
		)
		(property "License" "Apache-2.0"
			(at 48.975 219.375 0)
			(layer "F.Fab")
			(hide yes)
			(effects
				(font
					(size 1 1)
					(thickness 0.15)
				)
			)
		)
		(property "MPN" "GRM155R61A475MEAAD"
			(at 48.975 219.375 0)
			(layer "F.Fab")
			(hide yes)
			(effects
				(font
					(size 1 1)
					(thickness 0.15)
				)
			)
		)
		(property "Manufacturer" "Murata"
			(at 48.975 219.375 0)
			(layer "F.Fab")
			(hide yes)
			(effects
				(font
					(size 1 1)
					(thickness 0.15)
				)
			)
		)
		(property "Val" "4u7"
			(at 48.975 219.375 0)
			(layer "F.Fab")
			(hide yes)
			(effects
				(font
					(size 1 1)
					(thickness 0.15)
				)
			)
		)
		(property "Voltage" ""
			(at 48.975 219.375 0)
			(layer "F.Fab")
			(hide yes)
			(effects
				(font
					(size 1 1)
					(thickness 0.15)
				)
			)
		)
		(sheetname "EEPROM")
		(sheetfile "EEPROM.kicad_sch")
		(attr smd)
		(fp_rect
			(start -0.94 -0.47)
			(end 0.94 0.47)
			(stroke
				(width 0.05)
				(type solid)
			)
			(fill no)
			(layer "F.CrtYd")
		)
		(fp_rect
			(start -0.499 -0.249)
			(end 0.499 0.249)
			(stroke
				(width 0.15)
				(type solid)
			)
			(fill no)
			(layer "F.Fab")
		)
		(pad "1" smd roundrect
			(at -0.484 0 270)
			(size 0.59 0.64)
			(layers "F.Cu" "F.Mask" "F.Paste")
			(roundrect_rratio 0.25)
			(net 36 "GND")
			(pintype "passive")
		)
		(pad "2" smd roundrect
			(at 0.484 0 270)
			(size 0.59 0.64)
			(layers "F.Cu" "F.Mask" "F.Paste")
			(roundrect_rratio 0.25)
			(net 187 "VDD1")
			(pintype "passive")
		)
	)
	(footprint "antmicro-footprints:C_0402_1005Metric"
		(layer "F.Cu")
		(at 130.66 81.15 180)
		(descr "Capacitor SMD 0402")
		(tags "capacitor SMD 0402")
		(property "Reference" "C37"
			(at -0.915 0.6 0)
			(layer "F.SilkS")
			(effects
				(font
					(size 0.7 0.7)
					(thickness 0.15)
				)
				(justify right bottom)
			)
		)
		(property "Value" "C_4u7_0402"
			(at 0 1.4 0)
			(layer "F.Fab")
			(effects
				(font
					(size 0.7 0.7)
					(thickness 0.15)
				)
				(justify right bottom)
			)
		)
		(property "Description" " "
			(at 0 0 180)
			(layer "F.Fab")
			(hide yes)
			(effects
				(font
					(size 1.27 1.27)
					(thickness 0.15)
				)
			)
		)
		(property "Author" "Antmicro"
			(at 261.32 162.3 0)
			(layer "F.Fab")
			(hide yes)
			(effects
				(font
					(size 1 1)
					(thickness 0.15)
				)
			)
		)
		(property "License" "Apache-2.0"
			(at 261.32 162.3 0)
			(layer "F.Fab")
			(hide yes)
			(effects
				(font
					(size 1 1)
					(thickness 0.15)
				)
			)
		)
		(property "MPN" "GRM155R61A475MEAAD"
			(at 261.32 162.3 0)
			(layer "F.Fab")
			(hide yes)
			(effects
				(font
					(size 1 1)
					(thickness 0.15)
				)
			)
		)
		(property "Manufacturer" "Murata"
			(at 261.32 162.3 0)
			(layer "F.Fab")
			(hide yes)
			(effects
				(font
					(size 1 1)
					(thickness 0.15)
				)
			)
		)
		(property "Val" "4u7"
			(at 261.32 162.3 0)
			(layer "F.Fab")
			(hide yes)
			(effects
				(font
					(size 1 1)
					(thickness 0.15)
				)
			)
		)
		(sheetname "EEPROM")
		(sheetfile "EEPROM.kicad_sch")
		(attr smd)
		(fp_rect
			(start -0.94 -0.47)
			(end 0.94 0.47)
			(stroke
				(width 0.05)
				(type solid)
			)
			(fill no)
			(layer "F.CrtYd")
		)
		(fp_rect
			(start -0.499 -0.249)
			(end 0.499 0.249)
			(stroke
				(width 0.15)
				(type solid)
			)
			(fill no)
			(layer "F.Fab")
		)
		(pad "1" smd roundrect
			(at -0.484 0 180)
			(size 0.59 0.64)
			(layers "F.Cu" "F.Mask" "F.Paste")
			(roundrect_rratio 0.25)
			(net 36 "GND")
			(pintype "passive")
		)
		(pad "2" smd roundrect
			(at 0.484 0 180)
			(size 0.59 0.64)
			(layers "F.Cu" "F.Mask" "F.Paste")
			(roundrect_rratio 0.25)
			(net 241 "VDDLED")
			(pintype "passive")
		)
	)
	(footprint "antmicro-footprints:C_0402_1005Metric"
		(layer "F.Cu")
		(at 122.76 81.545 180)
		(descr "Capacitor SMD 0402")
		(tags "capacitor SMD 0402")
		(property "Reference" "C38"
			(at -1.015 0.595 0)
			(layer "F.SilkS")
			(effects
				(font
					(size 0.7 0.7)
					(thickness 0.15)
				)
				(justify right bottom)
			)
		)
		(property "Value" "C_100n_0402"
			(at 0 1.4 0)
			(layer "F.Fab")
			(effects
				(font
					(size 0.7 0.7)
					(thickness 0.15)
				)
				(justify right bottom)
			)
		)
		(property "Description" " "
			(at 0 0 180)
			(layer "F.Fab")
			(hide yes)
			(effects
				(font
					(size 1.27 1.27)
					(thickness 0.15)
				)
			)
		)
		(property "Author" "Antmicro"
			(at 245.52 163.09 0)
			(layer "F.Fab")
			(hide yes)
			(effects
				(font
					(size 1 1)
					(thickness 0.15)
				)
			)
		)
		(property "Dielectric" "X5R"
			(at 245.52 163.09 0)
			(layer "F.Fab")
			(hide yes)
			(effects
				(font
					(size 1 1)
					(thickness 0.15)
				)
			)
		)
		(property "License" "Apache-2.0"
			(at 245.52 163.09 0)
			(layer "F.Fab")
			(hide yes)
			(effects
				(font
					(size 1 1)
					(thickness 0.15)
				)
			)
		)
		(property "MPN" "0402X104K6R3CT"
			(at 245.52 163.09 0)
			(layer "F.Fab")
			(hide yes)
			(effects
				(font
					(size 1 1)
					(thickness 0.15)
				)
			)
		)
		(property "Manufacturer" "Walsin"
			(at 245.52 163.09 0)
			(layer "F.Fab")
			(hide yes)
			(effects
				(font
					(size 1 1)
					(thickness 0.15)
				)
			)
		)
		(property "Val" "100n"
			(at 245.52 163.09 0)
			(layer "F.Fab")
			(hide yes)
			(effects
				(font
					(size 1 1)
					(thickness 0.15)
				)
			)
		)
		(property "Voltage" "50V"
			(at 245.52 163.09 0)
			(layer "F.Fab")
			(hide yes)
			(effects
				(font
					(size 1 1)
					(thickness 0.15)
				)
			)
		)
		(sheetname "EEPROM")
		(sheetfile "EEPROM.kicad_sch")
		(attr smd)
		(fp_rect
			(start -0.94 -0.47)
			(end 0.94 0.47)
			(stroke
				(width 0.05)
				(type solid)
			)
			(fill no)
			(layer "F.CrtYd")
		)
		(fp_rect
			(start -0.499 -0.249)
			(end 0.499 0.249)
			(stroke
				(width 0.15)
				(type solid)
			)
			(fill no)
			(layer "F.Fab")
		)
		(pad "1" smd roundrect
			(at -0.484 0 180)
			(size 0.59 0.64)
			(layers "F.Cu" "F.Mask" "F.Paste")
			(roundrect_rratio 0.25)
			(net 36 "GND")
			(pintype "passive")
		)
		(pad "2" smd roundrect
			(at 0.484 0 180)
			(size 0.59 0.64)
			(layers "F.Cu" "F.Mask" "F.Paste")
			(roundrect_rratio 0.25)
			(net 187 "VDD1")
			(pintype "passive")
		)
	)
	(footprint "antmicro-footprints:LED_0603_1608Metric_G"
		(layer "F.Cu")
		(at 133.075 72.9 90)
		(descr "LED SMD 0603 Green")
		(tags "LED SMD 0603 Green")
		(property "Reference" "D4"
			(at 1.25 0.32 90)
			(layer "F.SilkS")
			(effects
				(font
					(size 0.7 0.7)
					(thickness 0.15)
				)
				(justify left bottom)
			)
		)
		(property "Value" "LED_G_0603_KP-1608CGCK"
			(at 0 1.6 90)
			(layer "F.Fab")
			(effects
				(font
					(size 0.7 0.7)
					(thickness 0.15)
				)
				(justify left bottom)
			)
		)
		(property "Author" "Antmicro"
			(at 205.975 -60.175 0)
			(layer "F.Fab")
			(hide yes)
			(effects
				(font
					(size 1 1)
					(thickness 0.15)
				)
			)
		)
		(property "License" "Apache-2.0"
			(at 205.975 -60.175 0)
			(layer "F.Fab")
			(hide yes)
			(effects
				(font
					(size 1 1)
					(thickness 0.15)
				)
			)
		)
		(property "MPN" "KP-1608CGCK"
			(at 205.975 -60.175 0)
			(layer "F.Fab")
			(hide yes)
			(effects
				(font
					(size 1 1)
					(thickness 0.15)
				)
			)
		)
		(property "Manufacturer" "Kingbright"
			(at 205.975 -60.175 0)
			(layer "F.Fab")
			(hide yes)
			(effects
				(font
					(size 1 1)
					(thickness 0.15)
				)
			)
		)
		(sheetname "EEPROM")
		(sheetfile "EEPROM.kicad_sch")
		(attr smd)
		(fp_line
			(start -0.27 -0.35)
			(end 0.27 -0.35)
			(stroke
				(width 0.15)
				(type solid)
			)
			(layer "F.SilkS")
		)
		(fp_line
			(start 0.093672 -0.200008)
			(end 0.093672 0.199992)
			(stroke
				(width 0.1)
				(type solid)
			)
			(layer "F.SilkS")
		)
		(fp_line
			(start -0.106328 -0.200008)
			(end 0.093672 -8e-06)
			(stroke
				(width 0.1)
				(type solid)
			)
			(layer "F.SilkS")
		)
		(fp_line
			(start -0.106328 -0.200008)
			(end -0.106328 0.199992)
			(stroke
				(width 0.1)
				(type solid)
			)
			(layer "F.SilkS")
		)
		(fp_line
			(start 0.093672 -8e-06)
			(end 0.293672 -8e-06)
			(stroke
				(width 0.1)
				(type solid)
			)
			(layer "F.SilkS")
		)
		(fp_line
			(start 0.093672 -8e-06)
			(end -0.106328 0.199992)
			(stroke
				(width 0.1)
				(type solid)
			)
			(layer "F.SilkS")
		)
		(fp_line
			(start -0.106328 -8e-06)
			(end -0.29 0)
			(stroke
				(width 0.1)
				(type solid)
			)
			(layer "F.SilkS")
		)
		(fp_line
			(start 1.25 0.32)
			(end 1.25 -0.32)
			(stroke
				(width 0.15)
				(type solid)
			)
			(layer "F.SilkS")
		)
		(fp_line
			(start -0.27 0.351)
			(end 0.27 0.351)
			(stroke
				(width 0.15)
				(type solid)
			)
			(layer "F.SilkS")
		)
		(fp_rect
			(start 1.26 0.65)
			(end -1.26 -0.65)
			(stroke
				(width 0.05)
				(type solid)
			)
			(fill no)
			(layer "F.CrtYd")
		)
		(fp_line
			(start 0.199 -0.2)
			(end 0.199 -0.1)
			(stroke
				(width 0.15)
				(type solid)
			)
			(layer "F.Fab")
		)
		(fp_line
			(start -0.201 -0.2)
			(end -0.201 0)
			(stroke
				(width 0.15)
				(type solid)
			)
			(layer "F.Fab")
		)
		(fp_line
			(start 0.199 0)
			(end 0.597 0)
			(stroke
				(width 0.15)
				(type solid)
			)
			(layer "F.Fab")
		)
		(fp_line
			(start 0.101 0)
			(end -0.201 -0.2)
			(stroke
				(width 0.15)
				(type solid)
			)
			(layer "F.Fab")
		)
		(fp_line
			(start -0.201 0)
			(end -0.201 0.202)
			(stroke
				(width 0.15)
				(type solid)
			)
			(layer "F.Fab")
		)
		(fp_line
			(start -0.599 0)
			(end -0.201 0)
			(stroke
				(width 0.15)
				(type solid)
			)
			(layer "F.Fab")
		)
		(fp_line
			(start 0.199 0.202)
			(end 0.199 -0.1)
			(stroke
				(width 0.15)
				(type solid)
			)
			(layer "F.Fab")
		)
		(fp_line
			(start -0.201 0.202)
			(end 0.101 0)
			(stroke
				(width 0.15)
				(type solid)
			)
			(layer "F.Fab")
		)
		(fp_rect
			(start -0.848 -0.4)
			(end 0.85 0.402)
			(stroke
				(width 0.15)
				(type solid)
			)
			(fill no)
			(layer "F.Fab")
		)
		(pad "1" smd rect
			(at -0.75 0 270)
			(size 0.8 0.8)
			(layers "F.Cu" "F.Mask" "F.Paste")
			(net 258 "Net-(D4-Pad1)")
			(pinfunction "1")
			(pintype "passive")
		)
		(pad "2" smd rect
			(at 0.75 0 270)
			(size 0.8 0.8)
			(layers "F.Cu" "F.Mask" "F.Paste")
			(net 36 "GND")
			(pinfunction "2")
			(pintype "passive")
		)
	)
	(footprint "antmicro-footprints:LED_0603_1608Metric_G"
		(layer "F.Cu")
		(at 131.258332 72.9 90)
		(descr "LED SMD 0603 Green")
		(tags "LED SMD 0603 Green")
		(property "Reference" "D3"
			(at 1.25 0.32 90)
			(layer "F.SilkS")
			(effects
				(font
					(size 0.7 0.7)
					(thickness 0.15)
				)
				(justify left bottom)
			)
		)
		(property "Value" "LED_G_0603_KP-1608CGCK"
			(at 0 1.6 90)
			(layer "F.Fab")
			(effects
				(font
					(size 0.7 0.7)
					(thickness 0.15)
				)
				(justify left bottom)
			)
		)
		(property "Author" "Antmicro"
			(at 204.158332 -58.358332 0)
			(layer "F.Fab")
			(hide yes)
			(effects
				(font
					(size 1 1)
					(thickness 0.15)
				)
			)
		)
		(property "License" "Apache-2.0"
			(at 204.158332 -58.358332 0)
			(layer "F.Fab")
			(hide yes)
			(effects
				(font
					(size 1 1)
					(thickness 0.15)
				)
			)
		)
		(property "MPN" "KP-1608CGCK"
			(at 204.158332 -58.358332 0)
			(layer "F.Fab")
			(hide yes)
			(effects
				(font
					(size 1 1)
					(thickness 0.15)
				)
			)
		)
		(property "Manufacturer" "Kingbright"
			(at 204.158332 -58.358332 0)
			(layer "F.Fab")
			(hide yes)
			(effects
				(font
					(size 1 1)
					(thickness 0.15)
				)
			)
		)
		(sheetname "EEPROM")
		(sheetfile "EEPROM.kicad_sch")
		(attr smd)
		(fp_line
			(start -0.27 -0.35)
			(end 0.27 -0.35)
			(stroke
				(width 0.15)
				(type solid)
			)
			(layer "F.SilkS")
		)
		(fp_line
			(start 0.093672 -0.200008)
			(end 0.093672 0.199992)
			(stroke
				(width 0.1)
				(type solid)
			)
			(layer "F.SilkS")
		)
		(fp_line
			(start -0.106328 -0.200008)
			(end 0.093672 -8e-06)
			(stroke
				(width 0.1)
				(type solid)
			)
			(layer "F.SilkS")
		)
		(fp_line
			(start -0.106328 -0.200008)
			(end -0.106328 0.199992)
			(stroke
				(width 0.1)
				(type solid)
			)
			(layer "F.SilkS")
		)
		(fp_line
			(start 0.093672 -8e-06)
			(end 0.293672 -8e-06)
			(stroke
				(width 0.1)
				(type solid)
			)
			(layer "F.SilkS")
		)
		(fp_line
			(start 0.093672 -8e-06)
			(end -0.106328 0.199992)
			(stroke
				(width 0.1)
				(type solid)
			)
			(layer "F.SilkS")
		)
		(fp_line
			(start -0.106328 -8e-06)
			(end -0.29 0)
			(stroke
				(width 0.1)
				(type solid)
			)
			(layer "F.SilkS")
		)
		(fp_line
			(start 1.25 0.32)
			(end 1.25 -0.32)
			(stroke
				(width 0.15)
				(type solid)
			)
			(layer "F.SilkS")
		)
		(fp_line
			(start -0.27 0.351)
			(end 0.27 0.351)
			(stroke
				(width 0.15)
				(type solid)
			)
			(layer "F.SilkS")
		)
		(fp_rect
			(start 1.26 0.65)
			(end -1.26 -0.65)
			(stroke
				(width 0.05)
				(type solid)
			)
			(fill no)
			(layer "F.CrtYd")
		)
		(fp_line
			(start 0.199 -0.2)
			(end 0.199 -0.1)
			(stroke
				(width 0.15)
				(type solid)
			)
			(layer "F.Fab")
		)
		(fp_line
			(start -0.201 -0.2)
			(end -0.201 0)
			(stroke
				(width 0.15)
				(type solid)
			)
			(layer "F.Fab")
		)
		(fp_line
			(start 0.199 0)
			(end 0.597 0)
			(stroke
				(width 0.15)
				(type solid)
			)
			(layer "F.Fab")
		)
		(fp_line
			(start 0.101 0)
			(end -0.201 -0.2)
			(stroke
				(width 0.15)
				(type solid)
			)
			(layer "F.Fab")
		)
		(fp_line
			(start -0.201 0)
			(end -0.201 0.202)
			(stroke
				(width 0.15)
				(type solid)
			)
			(layer "F.Fab")
		)
		(fp_line
			(start -0.599 0)
			(end -0.201 0)
			(stroke
				(width 0.15)
				(type solid)
			)
			(layer "F.Fab")
		)
		(fp_line
			(start 0.199 0.202)
			(end 0.199 -0.1)
			(stroke
				(width 0.15)
				(type solid)
			)
			(layer "F.Fab")
		)
		(fp_line
			(start -0.201 0.202)
			(end 0.101 0)
			(stroke
				(width 0.15)
				(type solid)
			)
			(layer "F.Fab")
		)
		(fp_rect
			(start -0.848 -0.4)
			(end 0.85 0.402)
			(stroke
				(width 0.15)
				(type solid)
			)
			(fill no)
			(layer "F.Fab")
		)
		(pad "1" smd rect
			(at -0.75 0 270)
			(size 0.8 0.8)
			(layers "F.Cu" "F.Mask" "F.Paste")
			(net 257 "Net-(D3-Pad1)")
			(pinfunction "1")
			(pintype "passive")
		)
		(pad "2" smd rect
			(at 0.75 0 270)
			(size 0.8 0.8)
			(layers "F.Cu" "F.Mask" "F.Paste")
			(net 36 "GND")
			(pinfunction "2")
			(pintype "passive")
		)
	)
	(footprint "antmicro-footprints:LED_0603_1608Metric_G"
		(layer "F.Cu")
		(at 127.625 72.9 90)
		(descr "LED SMD 0603 Green")
		(tags "LED SMD 0603 Green")
		(property "Reference" "D1"
			(at 1.25 0.32 90)
			(layer "F.SilkS")
			(effects
				(font
					(size 0.7 0.7)
					(thickness 0.15)
				)
				(justify left bottom)
			)
		)
		(property "Value" "LED_G_0603_KP-1608CGCK"
			(at 0 1.6 90)
			(layer "F.Fab")
			(effects
				(font
					(size 0.7 0.7)
					(thickness 0.15)
				)
				(justify left bottom)
			)
		)
		(property "Author" "Antmicro"
			(at 200.525 -54.725 0)
			(layer "F.Fab")
			(hide yes)
			(effects
				(font
					(size 1 1)
					(thickness 0.15)
				)
			)
		)
		(property "License" "Apache-2.0"
			(at 200.525 -54.725 0)
			(layer "F.Fab")
			(hide yes)
			(effects
				(font
					(size 1 1)
					(thickness 0.15)
				)
			)
		)
		(property "MPN" "KP-1608CGCK"
			(at 200.525 -54.725 0)
			(layer "F.Fab")
			(hide yes)
			(effects
				(font
					(size 1 1)
					(thickness 0.15)
				)
			)
		)
		(property "Manufacturer" "Kingbright"
			(at 200.525 -54.725 0)
			(layer "F.Fab")
			(hide yes)
			(effects
				(font
					(size 1 1)
					(thickness 0.15)
				)
			)
		)
		(sheetname "EEPROM")
		(sheetfile "EEPROM.kicad_sch")
		(attr smd)
		(fp_line
			(start -0.27 -0.35)
			(end 0.27 -0.35)
			(stroke
				(width 0.15)
				(type solid)
			)
			(layer "F.SilkS")
		)
		(fp_line
			(start 0.093672 -0.200008)
			(end 0.093672 0.199992)
			(stroke
				(width 0.1)
				(type solid)
			)
			(layer "F.SilkS")
		)
		(fp_line
			(start -0.106328 -0.200008)
			(end 0.093672 -8e-06)
			(stroke
				(width 0.1)
				(type solid)
			)
			(layer "F.SilkS")
		)
		(fp_line
			(start -0.106328 -0.200008)
			(end -0.106328 0.199992)
			(stroke
				(width 0.1)
				(type solid)
			)
			(layer "F.SilkS")
		)
		(fp_line
			(start 0.093672 -8e-06)
			(end 0.293672 -8e-06)
			(stroke
				(width 0.1)
				(type solid)
			)
			(layer "F.SilkS")
		)
		(fp_line
			(start 0.093672 -8e-06)
			(end -0.106328 0.199992)
			(stroke
				(width 0.1)
				(type solid)
			)
			(layer "F.SilkS")
		)
		(fp_line
			(start -0.106328 -8e-06)
			(end -0.29 0)
			(stroke
				(width 0.1)
				(type solid)
			)
			(layer "F.SilkS")
		)
		(fp_line
			(start 1.25 0.32)
			(end 1.25 -0.32)
			(stroke
				(width 0.15)
				(type solid)
			)
			(layer "F.SilkS")
		)
		(fp_line
			(start -0.27 0.351)
			(end 0.27 0.351)
			(stroke
				(width 0.15)
				(type solid)
			)
			(layer "F.SilkS")
		)
		(fp_rect
			(start 1.26 0.65)
			(end -1.26 -0.65)
			(stroke
				(width 0.05)
				(type solid)
			)
			(fill no)
			(layer "F.CrtYd")
		)
		(fp_line
			(start 0.199 -0.2)
			(end 0.199 -0.1)
			(stroke
				(width 0.15)
				(type solid)
			)
			(layer "F.Fab")
		)
		(fp_line
			(start -0.201 -0.2)
			(end -0.201 0)
			(stroke
				(width 0.15)
				(type solid)
			)
			(layer "F.Fab")
		)
		(fp_line
			(start 0.199 0)
			(end 0.597 0)
			(stroke
				(width 0.15)
				(type solid)
			)
			(layer "F.Fab")
		)
		(fp_line
			(start 0.101 0)
			(end -0.201 -0.2)
			(stroke
				(width 0.15)
				(type solid)
			)
			(layer "F.Fab")
		)
		(fp_line
			(start -0.201 0)
			(end -0.201 0.202)
			(stroke
				(width 0.15)
				(type solid)
			)
			(layer "F.Fab")
		)
		(fp_line
			(start -0.599 0)
			(end -0.201 0)
			(stroke
				(width 0.15)
				(type solid)
			)
			(layer "F.Fab")
		)
		(fp_line
			(start 0.199 0.202)
			(end 0.199 -0.1)
			(stroke
				(width 0.15)
				(type solid)
			)
			(layer "F.Fab")
		)
		(fp_line
			(start -0.201 0.202)
			(end 0.101 0)
			(stroke
				(width 0.15)
				(type solid)
			)
			(layer "F.Fab")
		)
		(fp_rect
			(start -0.848 -0.4)
			(end 0.85 0.402)
			(stroke
				(width 0.15)
				(type solid)
			)
			(fill no)
			(layer "F.Fab")
		)
		(pad "1" smd rect
			(at -0.75 0 270)
			(size 0.8 0.8)
			(layers "F.Cu" "F.Mask" "F.Paste")
			(net 255 "Net-(D1-Pad1)")
			(pinfunction "1")
			(pintype "passive")
		)
		(pad "2" smd rect
			(at 0.75 0 270)
			(size 0.8 0.8)
			(layers "F.Cu" "F.Mask" "F.Paste")
			(net 36 "GND")
			(pinfunction "2")
			(pintype "passive")
		)
	)
	(footprint "antmicro-footprints:SOT-23-5"
		(layer "F.Cu")
		(at 129.365 91.13)
		(property "Reference" "IC2"
			(at -0.99 2.82 0)
			(layer "F.SilkS")
			(effects
				(font
					(size 0.7 0.7)
					(thickness 0.15)
				)
				(justify left bottom)
			)
		)
		(property "Value" "AT24CS01_SOT23"
			(at 0.002 2.799 0)
			(layer "F.Fab")
			(effects
				(font
					(size 0.7 0.7)
					(thickness 0.15)
				)
				(justify left bottom)
			)
		)
		(property "Description" "SOT-23-5"
			(at 0 0 0)
			(layer "F.Fab")
			(hide yes)
			(effects
				(font
					(size 1.27 1.27)
					(thickness 0.15)
				)
			)
		)
		(property "Author" "Antmicro"
			(at 0 0 0)
			(layer "F.Fab")
			(hide yes)
			(effects
				(font
					(size 1 1)
					(thickness 0.15)
				)
			)
		)
		(property "License" "Apache-2.0"
			(at 0 0 0)
			(layer "F.Fab")
			(hide yes)
			(effects
				(font
					(size 1 1)
					(thickness 0.15)
				)
			)
		)
		(property "MPN" "AT24CS01-ST"
			(at 0 0 0)
			(layer "F.Fab")
			(hide yes)
			(effects
				(font
					(size 1 1)
					(thickness 0.15)
				)
			)
		)
		(property "Manufacturer" "Atmel"
			(at 0 0 0)
			(layer "F.Fab")
			(hide yes)
			(effects
				(font
					(size 1 1)
					(thickness 0.15)
				)
			)
		)
		(sheetname "EEPROM")
		(sheetfile "EEPROM.kicad_sch")
		(attr smd)
		(fp_line
			(start -0.85 1.6)
			(end -0.85 1.301)
			(stroke
				(width 0.15)
				(type solid)
			)
			(layer "F.SilkS")
		)
		(fp_line
			(start -0.8 -1.6)
			(end -0.8 -1.3)
			(stroke
				(width 0.15)
				(type solid)
			)
			(layer "F.SilkS")
		)
		(fp_line
			(start -0.8 -1.6)
			(end -0.5 -1.6)
			(stroke
				(width 0.15)
				(type solid)
			)
			(layer "F.SilkS")
		)
		(fp_line
			(start -0.55 1.6)
			(end -0.85 1.6)
			(stroke
				(width 0.15)
				(type solid)
			)
			(layer "F.SilkS")
		)
		(fp_line
			(start 0.8 -1.6)
			(end 0.5 -1.6)
			(stroke
				(width 0.15)
				(type solid)
			)
			(layer "F.SilkS")
		)
		(fp_line
			(start 0.8 -1.3)
			(end 0.8 -1.6)
			(stroke
				(width 0.15)
				(type solid)
			)
			(layer "F.SilkS")
		)
		(fp_line
			(start 0.8 0.55)
			(end 0.8 -0.55)
			(stroke
				(width 0.15)
				(type solid)
			)
			(layer "F.SilkS")
		)
		(fp_line
			(start 0.8 1.3)
			(end 0.8 1.599)
			(stroke
				(width 0.15)
				(type solid)
			)
			(layer "F.SilkS")
		)
		(fp_line
			(start 0.8 1.599)
			(end 0.549 1.599)
			(stroke
				(width 0.15)
				(type solid)
			)
			(layer "F.SilkS")
		)
		(fp_circle
			(center -1.25 -1.5)
			(end -1.2 -1.5)
			(stroke
				(width 0.15)
				(type solid)
			)
			(fill yes)
			(layer "F.SilkS")
		)
		(fp_rect
			(start 1.9 -1.76)
			(end -1.9 1.75)
			(stroke
				(width 0.05)
				(type solid)
			)
			(fill no)
			(layer "F.CrtYd")
		)
		(fp_line
			(start -0.398 -1.526)
			(end -0.874 -1.05)
			(stroke
				(width 0.15)
				(type solid)
			)
			(layer "F.Fab")
		)
		(fp_rect
			(start 0.874 1.523)
			(end -0.873 -1.525)
			(stroke
				(width 0.15)
				(type solid)
			)
			(fill no)
			(layer "F.Fab")
		)
		(pad "1" smd rect
			(at -1.351 -0.951 270)
			(size 0.55 1)
			(layers "F.Cu" "F.Mask" "F.Paste")
			(net 247 "SCL")
			(pinfunction "SCL")
			(pintype "passive")
		)
		(pad "2" smd rect
			(at -1.351 0 270)
			(size 0.55 1)
			(layers "F.Cu" "F.Mask" "F.Paste")
			(net 36 "GND")
			(pinfunction "GND")
			(pintype "passive")
		)
		(pad "3" smd rect
			(at -1.351 0.949 270)
			(size 0.55 1)
			(layers "F.Cu" "F.Mask" "F.Paste")
			(net 246 "SDA")
			(pinfunction "SDA")
			(pintype "passive")
		)
		(pad "4" smd rect
			(at 1.35 0.949 270)
			(size 0.55 1)
			(layers "F.Cu" "F.Mask" "F.Paste")
			(net 187 "VDD1")
			(pinfunction "VCC")
			(pintype "passive")
		)
		(pad "5" smd rect
			(at 1.35 -0.951 270)
			(size 0.55 1)
			(layers "F.Cu" "F.Mask" "F.Paste")
			(net 36 "GND")
			(pinfunction "WP")
			(pintype "passive")
		)
	)
	(footprint "lpddr4-testbed-footprints:L_0806_2016Metric"
		(layer "F.Cu")
		(at 131.725 86.45 180)
		(property "Reference" "L1"
			(at 0 -1.2 180)
			(layer "F.SilkS")
			(effects
				(font
					(size 0.7 0.7)
					(thickness 0.15)
				)
				(justify left bottom)
			)
		)
		(property "Value" "L_2u2_1.5A_1285AS-H"
			(at 0 2 180)
			(layer "F.Fab")
			(effects
				(font
					(size 0.7 0.7)
					(thickness 0.15)
				)
				(justify left bottom)
			)
		)
		(property "Author" "Antmicro"
			(at 263.45 172.9 0)
			(layer "F.Fab")
			(hide yes)
			(effects
				(font
					(size 1 1)
					(thickness 0.15)
				)
			)
		)
		(property "IMax" ""
			(at 263.45 172.9 0)
			(layer "F.Fab")
			(hide yes)
			(effects
				(font
					(size 1 1)
					(thickness 0.15)
				)
			)
		)
		(property "ISat" ""
			(at 263.45 172.9 0)
			(layer "F.Fab")
			(hide yes)
			(effects
				(font
					(size 1 1)
					(thickness 0.15)
				)
			)
		)
		(property "Imax" "1.5A"
			(at 263.45 172.9 0)
			(layer "F.Fab")
			(hide yes)
			(effects
				(font
					(size 1 1)
					(thickness 0.15)
				)
			)
		)
		(property "Isat" "1.2A"
			(at 263.45 172.9 0)
			(layer "F.Fab")
			(hide yes)
			(effects
				(font
					(size 1 1)
					(thickness 0.15)
				)
			)
		)
		(property "License" "Apache-2.0"
			(at 263.45 172.9 0)
			(layer "F.Fab")
			(hide yes)
			(effects
				(font
					(size 1 1)
					(thickness 0.15)
				)
			)
		)
		(property "MPN" "1285AS-H-2R2M=P2"
			(at 263.45 172.9 0)
			(layer "F.Fab")
			(hide yes)
			(effects
				(font
					(size 1 1)
					(thickness 0.15)
				)
			)
		)
		(property "Manufacturer" "Murata"
			(at 263.45 172.9 0)
			(layer "F.Fab")
			(hide yes)
			(effects
				(font
					(size 1 1)
					(thickness 0.15)
				)
			)
		)
		(property "Size" "0806_2016Metric"
			(at 263.45 172.9 0)
			(layer "F.Fab")
			(hide yes)
			(effects
				(font
					(size 1 1)
					(thickness 0.15)
				)
			)
		)
		(property "Val" "2u2/1.5A"
			(at 263.45 172.9 0)
			(layer "F.Fab")
			(hide yes)
			(effects
				(font
					(size 1 1)
					(thickness 0.15)
				)
			)
		)
		(sheetname "EEPROM")
		(sheetfile "EEPROM.kicad_sch")
		(attr smd)
		(fp_line
			(start -0.3 -0.9)
			(end 0.298 -0.9)
			(stroke
				(width 0.15)
				(type solid)
			)
			(layer "F.SilkS")
		)
		(fp_line
			(start -0.301 0.9)
			(end 0.299 0.9)
			(stroke
				(width 0.15)
				(type solid)
			)
			(layer "F.SilkS")
		)
		(fp_rect
			(start -1.75 -1.05)
			(end 1.75 1.05)
			(stroke
				(width 0.05)
				(type solid)
			)
			(fill no)
			(layer "F.CrtYd")
		)
		(fp_rect
			(start -0.951 -0.882)
			(end 0.949 0.875)
			(stroke
				(width 0.15)
				(type solid)
			)
			(fill no)
			(layer "F.Fab")
		)
		(pad "1" smd roundrect
			(at -1.1 -0.001 180)
			(size 1 1.8)
			(layers "F.Cu" "F.Mask" "F.Paste")
			(roundrect_rratio 0.15)
			(net 187 "VDD1")
			(pintype "passive")
		)
		(pad "2" smd roundrect
			(at 1.1 -0.001 180)
			(size 1 1.8)
			(layers "F.Cu" "F.Mask" "F.Paste")
			(roundrect_rratio 0.15)
			(net 157 "Net-(U2-SW)")
			(pintype "passive")
		)
	)
	(footprint "antmicro-footprints:R_0402_1005Metric"
		(layer "F.Cu")
		(at 128.53 81.145 180)
		(descr "Resistor SMD 0402")
		(tags "resistor SMD 0402")
		(property "Reference" "R8"
			(at 0.755 0.595 180)
			(layer "F.SilkS")
			(effects
				(font
					(size 0.7 0.7)
					(thickness 0.15)
				)
				(justify left bottom)
			)
		)
		(property "Value" "R_0R_0402"
			(at 0 1.4 180)
			(layer "F.Fab")
			(effects
				(font
					(size 0.7 0.7)
					(thickness 0.15)
				)
				(justify left bottom)
			)
		)
		(property "Description" "0R resistor in 0402 package with unspecified tolerance"
			(at 0 0 180)
			(layer "F.Fab")
			(hide yes)
			(effects
				(font
					(size 1.27 1.27)
					(thickness 0.15)
				)
			)
		)
		(property "Author" "Antmicro"
			(at 257.06 162.29 0)
			(layer "F.Fab")
			(hide yes)
			(effects
				(font
					(size 1 1)
					(thickness 0.15)
				)
			)
		)
		(property "Current" "1A"
			(at 257.06 162.29 0)
			(layer "F.Fab")
			(hide yes)
			(effects
				(font
					(size 1 1)
					(thickness 0.15)
				)
			)
		)
		(property "License" "Apache-2.0"
			(at 257.06 162.29 0)
			(layer "F.Fab")
			(hide yes)
			(effects
				(font
					(size 1 1)
					(thickness 0.15)
				)
			)
		)
		(property "MPN" "ERJ2GE0R00X"
			(at 257.06 162.29 0)
			(layer "F.Fab")
			(hide yes)
			(effects
				(font
					(size 1 1)
					(thickness 0.15)
				)
			)
		)
		(property "Manufacturer" "Panasonic"
			(at 257.06 162.29 0)
			(layer "F.Fab")
			(hide yes)
			(effects
				(font
					(size 1 1)
					(thickness 0.15)
				)
			)
		)
		(property "Tolerance" ""
			(at 257.06 162.29 0)
			(layer "F.Fab")
			(hide yes)
			(effects
				(font
					(size 1 1)
					(thickness 0.15)
				)
			)
		)
		(property "Val" "0R"
			(at 257.06 162.29 0)
			(layer "F.Fab")
			(hide yes)
			(effects
				(font
					(size 1 1)
					(thickness 0.15)
				)
			)
		)
		(sheetname "EEPROM")
		(sheetfile "EEPROM.kicad_sch")
		(attr exclude_from_pos_files exclude_from_bom dnp)
		(fp_rect
			(start -0.93 -0.47)
			(end 0.93 0.47)
			(stroke
				(width 0.05)
				(type solid)
			)
			(fill no)
			(layer "F.CrtYd")
		)
		(fp_rect
			(start -0.5 -0.25)
			(end 0.5 0.25)
			(stroke
				(width 0.15)
				(type solid)
			)
			(fill no)
			(layer "F.Fab")
		)
		(pad "1" smd roundrect
			(at -0.485 0 180)
			(size 0.59 0.64)
			(layers "F.Cu" "F.Mask" "F.Paste")
			(roundrect_rratio 0.25)
			(net 187 "VDD1")
			(pintype "passive")
		)
		(pad "2" smd roundrect
			(at 0.485 0 180)
			(size 0.59 0.64)
			(layers "F.Cu" "F.Mask" "F.Paste")
			(roundrect_rratio 0.25)
			(net 241 "VDDLED")
			(pintype "passive")
		)
	)
	(footprint "antmicro-footprints:R_0402_1005Metric"
		(layer "F.Cu")
		(at 133.075 75.95 90)
		(descr "Resistor SMD 0402")
		(tags "resistor SMD 0402")
		(property "Reference" "R12"
			(at -1 -0.5 90)
			(layer "F.SilkS")
			(effects
				(font
					(size 0.7 0.7)
					(thickness 0.15)
				)
				(justify left bottom)
			)
		)
		(property "Value" "R_220R_0402"
			(at 0 1.4 90)
			(layer "F.Fab")
			(effects
				(font
					(size 0.7 0.7)
					(thickness 0.15)
				)
				(justify left bottom)
			)
		)
		(property "Description" "220R resistor in 0402 package with 1% tolerance"
			(at 0 0 90)
			(layer "F.Fab")
			(hide yes)
			(effects
				(font
					(size 1.27 1.27)
					(thickness 0.15)
				)
			)
		)
		(property "Author" "Antmicro"
			(at 209.025 -57.125 0)
			(layer "F.Fab")
			(hide yes)
			(effects
				(font
					(size 1 1)
					(thickness 0.15)
				)
			)
		)
		(property "License" "Apache-2.0"
			(at 209.025 -57.125 0)
			(layer "F.Fab")
			(hide yes)
			(effects
				(font
					(size 1 1)
					(thickness 0.15)
				)
			)
		)
		(property "MPN" "ERJ2GEJ221X"
			(at 209.025 -57.125 0)
			(layer "F.Fab")
			(hide yes)
			(effects
				(font
					(size 1 1)
					(thickness 0.15)
				)
			)
		)
		(property "Manufacturer" "Panasonic"
			(at 209.025 -57.125 0)
			(layer "F.Fab")
			(hide yes)
			(effects
				(font
					(size 1 1)
					(thickness 0.15)
				)
			)
		)
		(property "Tolerance" "1%"
			(at 209.025 -57.125 0)
			(layer "F.Fab")
			(hide yes)
			(effects
				(font
					(size 1 1)
					(thickness 0.15)
				)
			)
		)
		(property "Val" "220R"
			(at 209.025 -57.125 0)
			(layer "F.Fab")
			(hide yes)
			(effects
				(font
					(size 1 1)
					(thickness 0.15)
				)
			)
		)
		(sheetname "EEPROM")
		(sheetfile "EEPROM.kicad_sch")
		(attr smd)
		(fp_rect
			(start -0.93 -0.47)
			(end 0.93 0.47)
			(stroke
				(width 0.05)
				(type solid)
			)
			(fill no)
			(layer "F.CrtYd")
		)
		(fp_rect
			(start -0.5 -0.25)
			(end 0.5 0.25)
			(stroke
				(width 0.15)
				(type solid)
			)
			(fill no)
			(layer "F.Fab")
		)
		(pad "1" smd roundrect
			(at -0.485 0 90)
			(size 0.59 0.64)
			(layers "F.Cu" "F.Mask" "F.Paste")
			(roundrect_rratio 0.25)
			(net 151 "Net-(IC1-P3)")
			(pintype "passive")
		)
		(pad "2" smd roundrect
			(at 0.485 0 90)
			(size 0.59 0.64)
			(layers "F.Cu" "F.Mask" "F.Paste")
			(roundrect_rratio 0.25)
			(net 258 "Net-(D4-Pad1)")
			(pintype "passive")
		)
	)
	(footprint "antmicro-footprints:TP_SMD_0.75mm"
		(layer "F.Cu")
		(at 129.55 88.55)
		(property "Reference" "TP2"
			(at -1.075 -0.35 0)
			(layer "F.SilkS")
			(effects
				(font
					(size 0.7 0.7)
					(thickness 0.15)
				)
				(justify left bottom)
			)
		)
		(property "Value" "TP_0.75mm_SMD"
			(at 0 1.2 0)
			(layer "F.Fab")
			(effects
				(font
					(size 0.7 0.7)
					(thickness 0.15)
				)
				(justify left bottom)
			)
		)
		(property "Description" "Test Point 0.75mm"
			(at 0 0 0)
			(layer "F.Fab")
			(hide yes)
			(effects
				(font
					(size 1.27 1.27)
					(thickness 0.15)
				)
			)
		)
		(property "Author" "Antmicro"
			(at 0 0 0)
			(layer "F.Fab")
			(hide yes)
			(effects
				(font
					(size 1 1)
					(thickness 0.15)
				)
			)
		)
		(property "License" "Apache-2.0"
			(at 0 0 0)
			(layer "F.Fab")
			(hide yes)
			(effects
				(font
					(size 1 1)
					(thickness 0.15)
				)
			)
		)
		(property "MPN" ""
			(at 0 0 0)
			(layer "F.Fab")
			(hide yes)
			(effects
				(font
					(size 1 1)
					(thickness 0.15)
				)
			)
		)
		(property "Manufacturer" ""
			(at 0 0 0)
			(layer "F.Fab")
			(hide yes)
			(effects
				(font
					(size 1 1)
					(thickness 0.15)
				)
			)
		)
		(sheetname "EEPROM")
		(sheetfile "EEPROM.kicad_sch")
		(attr exclude_from_pos_files)
		(pad "1" smd circle
			(at 0 0)
			(size 0.75 0.75)
			(layers "F.Cu" "F.Mask")
			(net 153 "Net-(IC1-P5)")
			(pinfunction "1")
			(pintype "passive")
		)
	)
	(footprint "antmicro-footprints:TP_SMD_0.75mm"
		(layer "F.Cu")
		(at 131.125 88.55)
		(property "Reference" "TP3"
			(at 0.45 0.4 0)
			(layer "F.SilkS")
			(effects
				(font
					(size 0.7 0.7)
					(thickness 0.15)
				)
				(justify left bottom)
			)
		)
		(property "Value" "TP_0.75mm_SMD"
			(at 0 1.2 0)
			(layer "F.Fab")
			(effects
				(font
					(size 0.7 0.7)
					(thickness 0.15)
				)
				(justify left bottom)
			)
		)
		(property "Description" "Test Point 0.75mm"
			(at 0 0 0)
			(layer "F.Fab")
			(hide yes)
			(effects
				(font
					(size 1.27 1.27)
					(thickness 0.15)
				)
			)
		)
		(property "Author" "Antmicro"
			(at 0 0 0)
			(layer "F.Fab")
			(hide yes)
			(effects
				(font
					(size 1 1)
					(thickness 0.15)
				)
			)
		)
		(property "License" "Apache-2.0"
			(at 0 0 0)
			(layer "F.Fab")
			(hide yes)
			(effects
				(font
					(size 1 1)
					(thickness 0.15)
				)
			)
		)
		(property "MPN" ""
			(at 0 0 0)
			(layer "F.Fab")
			(hide yes)
			(effects
				(font
					(size 1 1)
					(thickness 0.15)
				)
			)
		)
		(property "Manufacturer" ""
			(at 0 0 0)
			(layer "F.Fab")
			(hide yes)
			(effects
				(font
					(size 1 1)
					(thickness 0.15)
				)
			)
		)
		(sheetname "EEPROM")
		(sheetfile "EEPROM.kicad_sch")
		(attr exclude_from_pos_files)
		(pad "1" smd circle
			(at 0 0)
			(size 0.75 0.75)
			(layers "F.Cu" "F.Mask")
			(net 36 "GND")
			(pinfunction "1")
			(pintype "passive")
		)
	)
	(footprint "antmicro-footprints:SOT-23-5"
		(layer "F.Cu")
		(at 131.575 83.55 180)
		(property "Reference" "U2"
			(at -0.4 2 180)
			(layer "F.SilkS")
			(effects
				(font
					(size 0.7 0.7)
					(thickness 0.15)
				)
				(justify left bottom)
			)
		)
		(property "Value" "TPS613221A_SOT-23-5"
			(at 0.002 2.799 180)
			(layer "F.Fab")
			(effects
				(font
					(size 0.7 0.7)
					(thickness 0.15)
				)
				(justify left bottom)
			)
		)
		(property "Description" "1.8-A switch current boost converter 6.5-μA Quiescent current"
			(at 0 0 180)
			(layer "F.Fab")
			(hide yes)
			(effects
				(font
					(size 1.27 1.27)
					(thickness 0.15)
				)
			)
		)
		(property "Author" "Antmicro"
			(at 263.15 167.1 0)
			(layer "F.Fab")
			(hide yes)
			(effects
				(font
					(size 1 1)
					(thickness 0.15)
				)
			)
		)
		(property "License" "Apache-2.0"
			(at 263.15 167.1 0)
			(layer "F.Fab")
			(hide yes)
			(effects
				(font
					(size 1 1)
					(thickness 0.15)
				)
			)
		)
		(property "MPN" "TPS613221ADBVT"
			(at 263.15 167.1 0)
			(layer "F.Fab")
			(hide yes)
			(effects
				(font
					(size 1 1)
					(thickness 0.15)
				)
			)
		)
		(property "Manufacturer" "Texas Instruments"
			(at 263.15 167.1 0)
			(layer "F.Fab")
			(hide yes)
			(effects
				(font
					(size 1 1)
					(thickness 0.15)
				)
			)
		)
		(sheetname "EEPROM")
		(sheetfile "EEPROM.kicad_sch")
		(attr smd)
		(fp_line
			(start 0.8 1.599)
			(end 0.549 1.599)
			(stroke
				(width 0.15)
				(type solid)
			)
			(layer "F.SilkS")
		)
		(fp_line
			(start 0.8 1.3)
			(end 0.8 1.599)
			(stroke
				(width 0.15)
				(type solid)
			)
			(layer "F.SilkS")
		)
		(fp_line
			(start 0.8 0.55)
			(end 0.8 -0.55)
			(stroke
				(width 0.15)
				(type solid)
			)
			(layer "F.SilkS")
		)
		(fp_line
			(start 0.8 -1.3)
			(end 0.8 -1.6)
			(stroke
				(width 0.15)
				(type solid)
			)
			(layer "F.SilkS")
		)
		(fp_line
			(start 0.8 -1.6)
			(end 0.5 -1.6)
			(stroke
				(width 0.15)
				(type solid)
			)
			(layer "F.SilkS")
		)
		(fp_line
			(start -0.55 1.6)
			(end -0.85 1.6)
			(stroke
				(width 0.15)
				(type solid)
			)
			(layer "F.SilkS")
		)
		(fp_line
			(start -0.8 -1.6)
			(end -0.5 -1.6)
			(stroke
				(width 0.15)
				(type solid)
			)
			(layer "F.SilkS")
		)
		(fp_line
			(start -0.8 -1.6)
			(end -0.8 -1.3)
			(stroke
				(width 0.15)
				(type solid)
			)
			(layer "F.SilkS")
		)
		(fp_line
			(start -0.85 1.6)
			(end -0.85 1.301)
			(stroke
				(width 0.15)
				(type solid)
			)
			(layer "F.SilkS")
		)
		(fp_circle
			(center -1.25 -1.5)
			(end -1.2 -1.5)
			(stroke
				(width 0.15)
				(type solid)
			)
			(fill yes)
			(layer "F.SilkS")
		)
		(fp_rect
			(start 1.9 -1.76)
			(end -1.9 1.75)
			(stroke
				(width 0.05)
				(type solid)
			)
			(fill no)
			(layer "F.CrtYd")
		)
		(fp_line
			(start -0.398 -1.526)
			(end -0.874 -1.05)
			(stroke
				(width 0.15)
				(type solid)
			)
			(layer "F.Fab")
		)
		(fp_rect
			(start 0.874 1.523)
			(end -0.873 -1.525)
			(stroke
				(width 0.15)
				(type solid)
			)
			(fill no)
			(layer "F.Fab")
		)
		(pad "1" smd rect
			(at -1.351 -0.951 90)
			(size 0.55 1)
			(layers "F.Cu" "F.Mask" "F.Paste")
			(net 157 "Net-(U2-SW)")
			(pinfunction "SW")
			(pintype "power_in")
		)
		(pad "2" smd rect
			(at -1.351 0 90)
			(size 0.55 1)
			(layers "F.Cu" "F.Mask" "F.Paste")
			(net 36 "GND")
			(pinfunction "GND")
			(pintype "power_in")
		)
		(pad "3" smd rect
			(at -1.351 0.949 90)
			(size 0.55 1)
			(layers "F.Cu" "F.Mask" "F.Paste")
			(net 260 "unconnected-(U2-NC-Pad3)")
			(pinfunction "NC")
			(pintype "no_connect")
		)
		(pad "4" smd rect
			(at 1.35 0.949 90)
			(size 0.55 1)
			(layers "F.Cu" "F.Mask" "F.Paste")
			(net 241 "VDDLED")
			(pinfunction "VOUT")
			(pintype "power_in")
		)
		(pad "5" smd rect
			(at 1.35 -0.951 90)
			(size 0.55 1)
			(layers "F.Cu" "F.Mask" "F.Paste")
			(net 261 "unconnected-(U2-NC-Pad5)")
			(pinfunction "NC")
			(pintype "no_connect")
		)
	)
	(footprint "antmicro-footprints:TSSOP-16_4.4x5mm_P0.65mm"
		(layer "F.Cu")
		(at 125.125 84.9)
		(property "Reference" "IC1"
			(at 0 -2.952 0)
			(layer "F.SilkS")
			(effects
				(font
					(size 0.7 0.7)
					(thickness 0.15)
				)
				(justify left bottom)
			)
		)
		(property "Value" "PCA6408A_TSSOP"
			(at 0 3.749 0)
			(layer "F.Fab")
			(effects
				(font
					(size 0.7 0.7)
					(thickness 0.15)
				)
				(justify left bottom)
			)
		)
		(property "Description" "Low-voltage, 8-bit I2C-bus and SMBus I/O expander"
			(at 0 0 0)
			(layer "F.Fab")
			(hide yes)
			(effects
				(font
					(size 1.27 1.27)
					(thickness 0.15)
				)
			)
		)
		(property "Author" "Antmicro"
			(at 0 0 0)
			(layer "F.Fab")
			(hide yes)
			(effects
				(font
					(size 1 1)
					(thickness 0.15)
				)
			)
		)
		(property "License" "Apache-2.0"
			(at 0 0 0)
			(layer "F.Fab")
			(hide yes)
			(effects
				(font
					(size 1 1)
					(thickness 0.15)
				)
			)
		)
		(property "MPN" "PCA6408APW"
			(at 0 0 0)
			(layer "F.Fab")
			(hide yes)
			(effects
				(font
					(size 1 1)
					(thickness 0.15)
				)
			)
		)
		(property "Manufacturer" "NXP"
			(at 0 0 0)
			(layer "F.Fab")
			(hide yes)
			(effects
				(font
					(size 1 1)
					(thickness 0.15)
				)
			)
		)
		(sheetname "EEPROM")
		(sheetfile "EEPROM.kicad_sch")
		(attr smd)
		(fp_line
			(start -2.149 -2.735)
			(end 2.25 -2.735)
			(stroke
				(width 0.15)
				(type solid)
			)
			(layer "F.SilkS")
		)
		(fp_line
			(start 0.051 2.733)
			(end -2.149 2.733)
			(stroke
				(width 0.15)
				(type solid)
			)
			(layer "F.SilkS")
		)
		(fp_line
			(start 0.051 2.733)
			(end 2.25 2.733)
			(stroke
				(width 0.15)
				(type solid)
			)
			(layer "F.SilkS")
		)
		(fp_circle
			(center -2.815 -3.05)
			(end -2.765 -3.05)
			(stroke
				(width 0.15)
				(type solid)
			)
			(fill yes)
			(layer "F.SilkS")
		)
		(fp_line
			(start -3.81 -2.75)
			(end -3.81 2.74)
			(stroke
				(width 0.05)
				(type solid)
			)
			(layer "F.CrtYd")
		)
		(fp_line
			(start -3.81 2.74)
			(end 3.89 2.74)
			(stroke
				(width 0.05)
				(type solid)
			)
			(layer "F.CrtYd")
		)
		(fp_line
			(start 3.89 -2.75)
			(end -3.81 -2.75)
			(stroke
				(width 0.05)
				(type solid)
			)
			(layer "F.CrtYd")
		)
		(fp_line
			(start 3.89 2.74)
			(end 3.89 -2.75)
			(stroke
				(width 0.05)
				(type solid)
			)
			(layer "F.CrtYd")
		)
		(fp_line
			(start -2.149 -1.5)
			(end -1.15 -2.5)
			(stroke
				(width 0.15)
				(type solid)
			)
			(layer "F.Fab")
		)
		(fp_line
			(start -2.149 2.499)
			(end -2.149 -1.5)
			(stroke
				(width 0.15)
				(type solid)
			)
			(layer "F.Fab")
		)
		(fp_line
			(start -1.15 -2.5)
			(end 2.25 -2.5)
			(stroke
				(width 0.15)
				(type solid)
			)
			(layer "F.Fab")
		)
		(fp_line
			(start 2.25 -2.5)
			(end 2.25 2.499)
			(stroke
				(width 0.15)
				(type solid)
			)
			(layer "F.Fab")
		)
		(fp_line
			(start 2.25 2.499)
			(end -2.149 2.499)
			(stroke
				(width 0.15)
				(type solid)
			)
			(layer "F.Fab")
		)
		(pad "1" smd rect
			(at -2.815 -2.275)
			(size 1.475 0.4)
			(layers "F.Cu" "F.Mask" "F.Paste")
			(net 187 "VDD1")
			(pinfunction "VDD(I2C)")
			(pintype "power_in")
		)
		(pad "2" smd rect
			(at -2.815 -1.625)
			(size 1.475 0.4)
			(layers "F.Cu" "F.Mask" "F.Paste")
			(net 187 "VDD1")
			(pinfunction "ADDR")
			(pintype "input")
		)
		(pad "3" smd rect
			(at -2.815 -0.975)
			(size 1.475 0.4)
			(layers "F.Cu" "F.Mask" "F.Paste")
			(net 187 "VDD1")
			(pinfunction "~{RESET}")
			(pintype "input")
		)
		(pad "4" smd rect
			(at -2.815 -0.325)
			(size 1.475 0.4)
			(layers "F.Cu" "F.Mask" "F.Paste")
			(net 1 "Net-(IC1-P0)")
			(pinfunction "P0")
			(pintype "bidirectional")
		)
		(pad "5" smd rect
			(at -2.815 0.325)
			(size 1.475 0.4)
			(layers "F.Cu" "F.Mask" "F.Paste")
			(net 2 "Net-(IC1-P1)")
			(pinfunction "P1")
			(pintype "bidirectional")
		)
		(pad "6" smd rect
			(at -2.815 0.975)
			(size 1.475 0.4)
			(layers "F.Cu" "F.Mask" "F.Paste")
			(net 3 "Net-(IC1-P2)")
			(pinfunction "P2")
			(pintype "bidirectional")
		)
		(pad "7" smd rect
			(at -2.815 1.625)
			(size 1.475 0.4)
			(layers "F.Cu" "F.Mask" "F.Paste")
			(net 151 "Net-(IC1-P3)")
			(pinfunction "P3")
			(pintype "bidirectional")
		)
		(pad "8" smd rect
			(at -2.815 2.275)
			(size 1.475 0.4)
			(layers "F.Cu" "F.Mask" "F.Paste")
			(net 36 "GND")
			(pinfunction "GND")
			(pintype "power_in")
		)
		(pad "9" smd rect
			(at 2.91 2.275)
			(size 1.475 0.4)
			(layers "F.Cu" "F.Mask" "F.Paste")
			(net 152 "Net-(IC1-P4)")
			(pinfunction "P4")
			(pintype "bidirectional")
		)
		(pad "10" smd rect
			(at 2.91 1.625)
			(size 1.475 0.4)
			(layers "F.Cu" "F.Mask" "F.Paste")
			(net 153 "Net-(IC1-P5)")
			(pinfunction "P5")
			(pintype "bidirectional")
		)
		(pad "11" smd rect
			(at 2.91 0.975)
			(size 1.475 0.4)
			(layers "F.Cu" "F.Mask" "F.Paste")
			(net 154 "unconnected-(IC1-P6-Pad11)")
			(pinfunction "P6")
			(pintype "bidirectional+no_connect")
		)
		(pad "12" smd rect
			(at 2.91 0.325)
			(size 1.475 0.4)
			(layers "F.Cu" "F.Mask" "F.Paste")
			(net 155 "unconnected-(IC1-P7-Pad12)")
			(pinfunction "P7")
			(pintype "bidirectional+no_connect")
		)
		(pad "13" smd rect
			(at 2.91 -0.325)
			(size 1.475 0.4)
			(layers "F.Cu" "F.Mask" "F.Paste")
			(net 156 "unconnected-(IC1-~{INT}-Pad13)")
			(pinfunction "~{INT}")
			(pintype "open_collector+no_connect")
		)
		(pad "14" smd rect
			(at 2.91 -0.975)
			(size 1.475 0.4)
			(layers "F.Cu" "F.Mask" "F.Paste")
			(net 247 "SCL")
			(pinfunction "SCL")
			(pintype "open_collector")
		)
		(pad "15" smd rect
			(at 2.91 -1.625)
			(size 1.475 0.4)
			(layers "F.Cu" "F.Mask" "F.Paste")
			(net 246 "SDA")
			(pinfunction "SDA")
			(pintype "open_collector")
		)
		(pad "16" smd rect
			(at 2.91 -2.275)
			(size 1.475 0.4)
			(layers "F.Cu" "F.Mask" "F.Paste")
			(net 241 "VDDLED")
			(pinfunction "VDD(P)")
			(pintype "power_in")
		)
	)
	(footprint "antmicro-footprints:LED_0603_1608Metric_G"
		(layer "F.Cu")
		(at 129.441666 72.9 90)
		(descr "LED SMD 0603 Green")
		(tags "LED SMD 0603 Green")
		(property "Reference" "D2"
			(at 1.25 0.32 90)
			(layer "F.SilkS")
			(effects
				(font
					(size 0.7 0.7)
					(thickness 0.15)
				)
				(justify left bottom)
			)
		)
		(property "Value" "LED_G_0603_KP-1608CGCK"
			(at 0 1.6 90)
			(layer "F.Fab")
			(effects
				(font
					(size 0.7 0.7)
					(thickness 0.15)
				)
				(justify left bottom)
			)
		)
		(property "Author" "Antmicro"
			(at 202.341666 -56.541666 0)
			(layer "F.Fab")
			(hide yes)
			(effects
				(font
					(size 1 1)
					(thickness 0.15)
				)
			)
		)
		(property "License" "Apache-2.0"
			(at 202.341666 -56.541666 0)
			(layer "F.Fab")
			(hide yes)
			(effects
				(font
					(size 1 1)
					(thickness 0.15)
				)
			)
		)
		(property "MPN" "KP-1608CGCK"
			(at 202.341666 -56.541666 0)
			(layer "F.Fab")
			(hide yes)
			(effects
				(font
					(size 1 1)
					(thickness 0.15)
				)
			)
		)
		(property "Manufacturer" "Kingbright"
			(at 202.341666 -56.541666 0)
			(layer "F.Fab")
			(hide yes)
			(effects
				(font
					(size 1 1)
					(thickness 0.15)
				)
			)
		)
		(sheetname "EEPROM")
		(sheetfile "EEPROM.kicad_sch")
		(attr smd)
		(fp_line
			(start -0.27 -0.35)
			(end 0.27 -0.35)
			(stroke
				(width 0.15)
				(type solid)
			)
			(layer "F.SilkS")
		)
		(fp_line
			(start 0.093672 -0.200008)
			(end 0.093672 0.199992)
			(stroke
				(width 0.1)
				(type solid)
			)
			(layer "F.SilkS")
		)
		(fp_line
			(start -0.106328 -0.200008)
			(end 0.093672 -8e-06)
			(stroke
				(width 0.1)
				(type solid)
			)
			(layer "F.SilkS")
		)
		(fp_line
			(start -0.106328 -0.200008)
			(end -0.106328 0.199992)
			(stroke
				(width 0.1)
				(type solid)
			)
			(layer "F.SilkS")
		)
		(fp_line
			(start 0.093672 -8e-06)
			(end 0.293672 -8e-06)
			(stroke
				(width 0.1)
				(type solid)
			)
			(layer "F.SilkS")
		)
		(fp_line
			(start 0.093672 -8e-06)
			(end -0.106328 0.199992)
			(stroke
				(width 0.1)
				(type solid)
			)
			(layer "F.SilkS")
		)
		(fp_line
			(start -0.106328 -8e-06)
			(end -0.29 0)
			(stroke
				(width 0.1)
				(type solid)
			)
			(layer "F.SilkS")
		)
		(fp_line
			(start 1.25 0.32)
			(end 1.25 -0.32)
			(stroke
				(width 0.15)
				(type solid)
			)
			(layer "F.SilkS")
		)
		(fp_line
			(start -0.27 0.351)
			(end 0.27 0.351)
			(stroke
				(width 0.15)
				(type solid)
			)
			(layer "F.SilkS")
		)
		(fp_rect
			(start 1.26 0.65)
			(end -1.26 -0.65)
			(stroke
				(width 0.05)
				(type solid)
			)
			(fill no)
			(layer "F.CrtYd")
		)
		(fp_line
			(start 0.199 -0.2)
			(end 0.199 -0.1)
			(stroke
				(width 0.15)
				(type solid)
			)
			(layer "F.Fab")
		)
		(fp_line
			(start -0.201 -0.2)
			(end -0.201 0)
			(stroke
				(width 0.15)
				(type solid)
			)
			(layer "F.Fab")
		)
		(fp_line
			(start 0.199 0)
			(end 0.597 0)
			(stroke
				(width 0.15)
				(type solid)
			)
			(layer "F.Fab")
		)
		(fp_line
			(start 0.101 0)
			(end -0.201 -0.2)
			(stroke
				(width 0.15)
				(type solid)
			)
			(layer "F.Fab")
		)
		(fp_line
			(start -0.201 0)
			(end -0.201 0.202)
			(stroke
				(width 0.15)
				(type solid)
			)
			(layer "F.Fab")
		)
		(fp_line
			(start -0.599 0)
			(end -0.201 0)
			(stroke
				(width 0.15)
				(type solid)
			)
			(layer "F.Fab")
		)
		(fp_line
			(start 0.199 0.202)
			(end 0.199 -0.1)
			(stroke
				(width 0.15)
				(type solid)
			)
			(layer "F.Fab")
		)
		(fp_line
			(start -0.201 0.202)
			(end 0.101 0)
			(stroke
				(width 0.15)
				(type solid)
			)
			(layer "F.Fab")
		)
		(fp_rect
			(start -0.848 -0.4)
			(end 0.85 0.402)
			(stroke
				(width 0.15)
				(type solid)
			)
			(fill no)
			(layer "F.Fab")
		)
		(pad "1" smd rect
			(at -0.75 0 270)
			(size 0.8 0.8)
			(layers "F.Cu" "F.Mask" "F.Paste")
			(net 256 "Net-(D2-Pad1)")
			(pinfunction "1")
			(pintype "passive")
		)
		(pad "2" smd rect
			(at 0.75 0 270)
			(size 0.8 0.8)
			(layers "F.Cu" "F.Mask" "F.Paste")
			(net 36 "GND")
			(pinfunction "2")
			(pintype "passive")
		)
	)
	(footprint "antmicro-footprints:R_0402_1005Metric"
		(layer "F.Cu")
		(at 127.625 75.95 90)
		(descr "Resistor SMD 0402")
		(tags "resistor SMD 0402")
		(property "Reference" "R9"
			(at -1 -0.5 90)
			(layer "F.SilkS")
			(effects
				(font
					(size 0.7 0.7)
					(thickness 0.15)
				)
				(justify left bottom)
			)
		)
		(property "Value" "R_220R_0402"
			(at 0 1.4 90)
			(layer "F.Fab")
			(effects
				(font
					(size 0.7 0.7)
					(thickness 0.15)
				)
				(justify left bottom)
			)
		)
		(property "Description" "220R resistor in 0402 package with 1% tolerance"
			(at 0 0 90)
			(layer "F.Fab")
			(hide yes)
			(effects
				(font
					(size 1.27 1.27)
					(thickness 0.15)
				)
			)
		)
		(property "Author" "Antmicro"
			(at 203.575 -51.675 0)
			(layer "F.Fab")
			(hide yes)
			(effects
				(font
					(size 1 1)
					(thickness 0.15)
				)
			)
		)
		(property "License" "Apache-2.0"
			(at 203.575 -51.675 0)
			(layer "F.Fab")
			(hide yes)
			(effects
				(font
					(size 1 1)
					(thickness 0.15)
				)
			)
		)
		(property "MPN" "ERJ2GEJ221X"
			(at 203.575 -51.675 0)
			(layer "F.Fab")
			(hide yes)
			(effects
				(font
					(size 1 1)
					(thickness 0.15)
				)
			)
		)
		(property "Manufacturer" "Panasonic"
			(at 203.575 -51.675 0)
			(layer "F.Fab")
			(hide yes)
			(effects
				(font
					(size 1 1)
					(thickness 0.15)
				)
			)
		)
		(property "Tolerance" "1%"
			(at 203.575 -51.675 0)
			(layer "F.Fab")
			(hide yes)
			(effects
				(font
					(size 1 1)
					(thickness 0.15)
				)
			)
		)
		(property "Val" "220R"
			(at 203.575 -51.675 0)
			(layer "F.Fab")
			(hide yes)
			(effects
				(font
					(size 1 1)
					(thickness 0.15)
				)
			)
		)
		(sheetname "EEPROM")
		(sheetfile "EEPROM.kicad_sch")
		(attr smd)
		(fp_rect
			(start -0.93 -0.47)
			(end 0.93 0.47)
			(stroke
				(width 0.05)
				(type solid)
			)
			(fill no)
			(layer "F.CrtYd")
		)
		(fp_rect
			(start -0.5 -0.25)
			(end 0.5 0.25)
			(stroke
				(width 0.15)
				(type solid)
			)
			(fill no)
			(layer "F.Fab")
		)
		(pad "1" smd roundrect
			(at -0.485 0 90)
			(size 0.59 0.64)
			(layers "F.Cu" "F.Mask" "F.Paste")
			(roundrect_rratio 0.25)
			(net 1 "Net-(IC1-P0)")
			(pintype "passive")
		)
		(pad "2" smd roundrect
			(at 0.485 0 90)
			(size 0.59 0.64)
			(layers "F.Cu" "F.Mask" "F.Paste")
			(roundrect_rratio 0.25)
			(net 255 "Net-(D1-Pad1)")
			(pintype "passive")
		)
	)
	(footprint "antmicro-footprints:R_0402_1005Metric"
		(layer "F.Cu")
		(at 129.441666 75.95 90)
		(descr "Resistor SMD 0402")
		(tags "resistor SMD 0402")
		(property "Reference" "R10"
			(at -1 -0.5 90)
			(layer "F.SilkS")
			(effects
				(font
					(size 0.7 0.7)
					(thickness 0.15)
				)
				(justify left bottom)
			)
		)
		(property "Value" "R_220R_0402"
			(at 0 1.4 90)
			(layer "F.Fab")
			(effects
				(font
					(size 0.7 0.7)
					(thickness 0.15)
				)
				(justify left bottom)
			)
		)
		(property "Description" "220R resistor in 0402 package with 1% tolerance"
			(at 0 0 90)
			(layer "F.Fab")
			(hide yes)
			(effects
				(font
					(size 1.27 1.27)
					(thickness 0.15)
				)
			)
		)
		(property "Author" "Antmicro"
			(at 205.391666 -53.491666 0)
			(layer "F.Fab")
			(hide yes)
			(effects
				(font
					(size 1 1)
					(thickness 0.15)
				)
			)
		)
		(property "License" "Apache-2.0"
			(at 205.391666 -53.491666 0)
			(layer "F.Fab")
			(hide yes)
			(effects
				(font
					(size 1 1)
					(thickness 0.15)
				)
			)
		)
		(property "MPN" "ERJ2GEJ221X"
			(at 205.391666 -53.491666 0)
			(layer "F.Fab")
			(hide yes)
			(effects
				(font
					(size 1 1)
					(thickness 0.15)
				)
			)
		)
		(property "Manufacturer" "Panasonic"
			(at 205.391666 -53.491666 0)
			(layer "F.Fab")
			(hide yes)
			(effects
				(font
					(size 1 1)
					(thickness 0.15)
				)
			)
		)
		(property "Tolerance" "1%"
			(at 205.391666 -53.491666 0)
			(layer "F.Fab")
			(hide yes)
			(effects
				(font
					(size 1 1)
					(thickness 0.15)
				)
			)
		)
		(property "Val" "220R"
			(at 205.391666 -53.491666 0)
			(layer "F.Fab")
			(hide yes)
			(effects
				(font
					(size 1 1)
					(thickness 0.15)
				)
			)
		)
		(sheetname "EEPROM")
		(sheetfile "EEPROM.kicad_sch")
		(attr smd)
		(fp_rect
			(start -0.93 -0.47)
			(end 0.93 0.47)
			(stroke
				(width 0.05)
				(type solid)
			)
			(fill no)
			(layer "F.CrtYd")
		)
		(fp_rect
			(start -0.5 -0.25)
			(end 0.5 0.25)
			(stroke
				(width 0.15)
				(type solid)
			)
			(fill no)
			(layer "F.Fab")
		)
		(pad "1" smd roundrect
			(at -0.485 0 90)
			(size 0.59 0.64)
			(layers "F.Cu" "F.Mask" "F.Paste")
			(roundrect_rratio 0.25)
			(net 2 "Net-(IC1-P1)")
			(pintype "passive")
		)
		(pad "2" smd roundrect
			(at 0.485 0 90)
			(size 0.59 0.64)
			(layers "F.Cu" "F.Mask" "F.Paste")
			(roundrect_rratio 0.25)
			(net 256 "Net-(D2-Pad1)")
			(pintype "passive")
		)
	)
	(footprint "antmicro-footprints:R_0402_1005Metric"
		(layer "F.Cu")
		(at 131.258332 75.95 90)
		(descr "Resistor SMD 0402")
		(tags "resistor SMD 0402")
		(property "Reference" "R11"
			(at -1 -0.5 90)
			(layer "F.SilkS")
			(effects
				(font
					(size 0.7 0.7)
					(thickness 0.15)
				)
				(justify left bottom)
			)
		)
		(property "Value" "R_220R_0402"
			(at 0 1.4 90)
			(layer "F.Fab")
			(effects
				(font
					(size 0.7 0.7)
					(thickness 0.15)
				)
				(justify left bottom)
			)
		)
		(property "Description" "220R resistor in 0402 package with 1% tolerance"
			(at 0 0 90)
			(layer "F.Fab")
			(hide yes)
			(effects
				(font
					(size 1.27 1.27)
					(thickness 0.15)
				)
			)
		)
		(property "Author" "Antmicro"
			(at 207.208332 -55.308332 0)
			(layer "F.Fab")
			(hide yes)
			(effects
				(font
					(size 1 1)
					(thickness 0.15)
				)
			)
		)
		(property "License" "Apache-2.0"
			(at 207.208332 -55.308332 0)
			(layer "F.Fab")
			(hide yes)
			(effects
				(font
					(size 1 1)
					(thickness 0.15)
				)
			)
		)
		(property "MPN" "ERJ2GEJ221X"
			(at 207.208332 -55.308332 0)
			(layer "F.Fab")
			(hide yes)
			(effects
				(font
					(size 1 1)
					(thickness 0.15)
				)
			)
		)
		(property "Manufacturer" "Panasonic"
			(at 207.208332 -55.308332 0)
			(layer "F.Fab")
			(hide yes)
			(effects
				(font
					(size 1 1)
					(thickness 0.15)
				)
			)
		)
		(property "Tolerance" "1%"
			(at 207.208332 -55.308332 0)
			(layer "F.Fab")
			(hide yes)
			(effects
				(font
					(size 1 1)
					(thickness 0.15)
				)
			)
		)
		(property "Val" "220R"
			(at 207.208332 -55.308332 0)
			(layer "F.Fab")
			(hide yes)
			(effects
				(font
					(size 1 1)
					(thickness 0.15)
				)
			)
		)
		(sheetname "EEPROM")
		(sheetfile "EEPROM.kicad_sch")
		(attr smd)
		(fp_rect
			(start -0.93 -0.47)
			(end 0.93 0.47)
			(stroke
				(width 0.05)
				(type solid)
			)
			(fill no)
			(layer "F.CrtYd")
		)
		(fp_rect
			(start -0.5 -0.25)
			(end 0.5 0.25)
			(stroke
				(width 0.15)
				(type solid)
			)
			(fill no)
			(layer "F.Fab")
		)
		(pad "1" smd roundrect
			(at -0.485 0 90)
			(size 0.59 0.64)
			(layers "F.Cu" "F.Mask" "F.Paste")
			(roundrect_rratio 0.25)
			(net 3 "Net-(IC1-P2)")
			(pintype "passive")
		)
		(pad "2" smd roundrect
			(at 0.485 0 90)
			(size 0.59 0.64)
			(layers "F.Cu" "F.Mask" "F.Paste")
			(roundrect_rratio 0.25)
			(net 257 "Net-(D3-Pad1)")
			(pintype "passive")
		)
	)
	(footprint "antmicro-footprints:TP_SMD_0.75mm"
		(layer "F.Cu")
		(at 127.975 88.55)
		(property "Reference" "TP1"
			(at -2.4 0 0)
			(layer "F.SilkS")
			(effects
				(font
					(size 0.7 0.7)
					(thickness 0.15)
				)
				(justify left bottom)
			)
		)
		(property "Value" "TP_0.75mm_SMD"
			(at 0 1.2 0)
			(layer "F.Fab")
			(effects
				(font
					(size 0.7 0.7)
					(thickness 0.15)
				)
				(justify left bottom)
			)
		)
		(property "Description" "Test Point 0.75mm"
			(at 0 0 0)
			(layer "F.Fab")
			(hide yes)
			(effects
				(font
					(size 1.27 1.27)
					(thickness 0.15)
				)
			)
		)
		(property "Author" "Antmicro"
			(at 0 0 0)
			(layer "F.Fab")
			(hide yes)
			(effects
				(font
					(size 1 1)
					(thickness 0.15)
				)
			)
		)
		(property "License" "Apache-2.0"
			(at 0 0 0)
			(layer "F.Fab")
			(hide yes)
			(effects
				(font
					(size 1 1)
					(thickness 0.15)
				)
			)
		)
		(property "MPN" ""
			(at 0 0 0)
			(layer "F.Fab")
			(hide yes)
			(effects
				(font
					(size 1 1)
					(thickness 0.15)
				)
			)
		)
		(property "Manufacturer" ""
			(at 0 0 0)
			(layer "F.Fab")
			(hide yes)
			(effects
				(font
					(size 1 1)
					(thickness 0.15)
				)
			)
		)
		(sheetname "EEPROM")
		(sheetfile "EEPROM.kicad_sch")
		(attr exclude_from_pos_files)
		(pad "1" smd circle
			(at 0 0)
			(size 0.75 0.75)
			(layers "F.Cu" "F.Mask")
			(net 152 "Net-(IC1-P4)")
			(pinfunction "1")
			(pintype "passive")
		)
	)
	(footprint "antmicro-footprints:C_0402_1005Metric"
		(layer "F.Cu")
		(at 132.175 91.615 -90)
		(descr "Capacitor SMD 0402")
		(tags "capacitor SMD 0402")
		(property "Reference" "C39"
			(at -1.065 -1.4 90)
			(layer "F.SilkS")
			(effects
				(font
					(size 0.7 0.7)
					(thickness 0.15)
				)
				(justify right bottom)
			)
		)
		(property "Value" "C_100n_0402"
			(at 0 1.4 90)
			(layer "F.Fab")
			(effects
				(font
					(size 0.7 0.7)
					(thickness 0.15)
				)
				(justify right bottom)
			)
		)
		(property "Description" " "
			(at 0 0 270)
			(layer "F.Fab")
			(hide yes)
			(effects
				(font
					(size 1.27 1.27)
					(thickness 0.15)
				)
			)
		)
		(property "Author" "Antmicro"
			(at 40.56 223.79 0)
			(layer "F.Fab")
			(hide yes)
			(effects
				(font
					(size 1 1)
					(thickness 0.15)
				)
			)
		)
		(property "Dielectric" "X5R"
			(at 40.56 223.79 0)
			(layer "F.Fab")
			(hide yes)
			(effects
				(font
					(size 1 1)
					(thickness 0.15)
				)
			)
		)
		(property "License" "Apache-2.0"
			(at 40.56 223.79 0)
			(layer "F.Fab")
			(hide yes)
			(effects
				(font
					(size 1 1)
					(thickness 0.15)
				)
			)
		)
		(property "MPN" "0402X104K6R3CT"
			(at 40.56 223.79 0)
			(layer "F.Fab")
			(hide yes)
			(effects
				(font
					(size 1 1)
					(thickness 0.15)
				)
			)
		)
		(property "Manufacturer" "Walsin"
			(at 40.56 223.79 0)
			(layer "F.Fab")
			(hide yes)
			(effects
				(font
					(size 1 1)
					(thickness 0.15)
				)
			)
		)
		(property "Val" "100n"
			(at 40.56 223.79 0)
			(layer "F.Fab")
			(hide yes)
			(effects
				(font
					(size 1 1)
					(thickness 0.15)
				)
			)
		)
		(property "Voltage" "50V"
			(at 40.56 223.79 0)
			(layer "F.Fab")
			(hide yes)
			(effects
				(font
					(size 1 1)
					(thickness 0.15)
				)
			)
		)
		(sheetname "EEPROM")
		(sheetfile "EEPROM.kicad_sch")
		(attr smd)
		(fp_rect
			(start -0.94 -0.47)
			(end 0.94 0.47)
			(stroke
				(width 0.05)
				(type solid)
			)
			(fill no)
			(layer "F.CrtYd")
		)
		(fp_rect
			(start -0.499 -0.249)
			(end 0.499 0.249)
			(stroke
				(width 0.15)
				(type solid)
			)
			(fill no)
			(layer "F.Fab")
		)
		(pad "1" smd roundrect
			(at -0.484 0 270)
			(size 0.59 0.64)
			(layers "F.Cu" "F.Mask" "F.Paste")
			(roundrect_rratio 0.25)
			(net 36 "GND")
			(pintype "passive")
		)
		(pad "2" smd roundrect
			(at 0.484 0 270)
			(size 0.59 0.64)
			(layers "F.Cu" "F.Mask" "F.Paste")
			(roundrect_rratio 0.25)
			(net 187 "VDD1")
			(pintype "passive")
		)
	)
	(footprint "antmicro-footprints:R_0402_1005Metric"
		(layer "F.Cu")
		(at 126.56 92.585 90)
		(descr "Resistor SMD 0402")
		(tags "resistor SMD 0402")
		(property "Reference" "R13"
			(at -1.165 -0.585 90)
			(layer "F.SilkS")
			(effects
				(font
					(size 0.7 0.7)
					(thickness 0.15)
				)
				(justify left bottom)
			)
		)
		(property "Value" "R_10k_0402"
			(at 0 1.4 90)
			(layer "F.Fab")
			(effects
				(font
					(size 0.7 0.7)
					(thickness 0.15)
				)
				(justify left bottom)
			)
		)
		(property "Description" "10k resistor in 0402 package with 1% tolerance"
			(at 0 0 90)
			(layer "F.Fab")
			(hide yes)
			(effects
				(font
					(size 1.27 1.27)
					(thickness 0.15)
				)
			)
		)
		(property "Author" "Antmicro"
			(at 219.145 -33.975 0)
			(layer "F.Fab")
			(hide yes)
			(effects
				(font
					(size 1 1)
					(thickness 0.15)
				)
			)
		)
		(property "License" "Apache-2.0"
			(at 219.145 -33.975 0)
			(layer "F.Fab")
			(hide yes)
			(effects
				(font
					(size 1 1)
					(thickness 0.15)
				)
			)
		)
		(property "MPN" "CRCW040210K0FKEDHP"
			(at 219.145 -33.975 0)
			(layer "F.Fab")
			(hide yes)
			(effects
				(font
					(size 1 1)
					(thickness 0.15)
				)
			)
		)
		(property "Manufacturer" "VISHAY"
			(at 219.145 -33.975 0)
			(layer "F.Fab")
			(hide yes)
			(effects
				(font
					(size 1 1)
					(thickness 0.15)
				)
			)
		)
		(property "Tolerance" "1%"
			(at 219.145 -33.975 0)
			(layer "F.Fab")
			(hide yes)
			(effects
				(font
					(size 1 1)
					(thickness 0.15)
				)
			)
		)
		(property "Val" "10k"
			(at 219.145 -33.975 0)
			(layer "F.Fab")
			(hide yes)
			(effects
				(font
					(size 1 1)
					(thickness 0.15)
				)
			)
		)
		(sheetname "EEPROM")
		(sheetfile "EEPROM.kicad_sch")
		(attr smd)
		(fp_rect
			(start -0.93 -0.47)
			(end 0.93 0.47)
			(stroke
				(width 0.05)
				(type solid)
			)
			(fill no)
			(layer "F.CrtYd")
		)
		(fp_rect
			(start -0.5 -0.25)
			(end 0.5 0.25)
			(stroke
				(width 0.15)
				(type solid)
			)
			(fill no)
			(layer "F.Fab")
		)
		(pad "1" smd roundrect
			(at -0.485 0 90)
			(size 0.59 0.64)
			(layers "F.Cu" "F.Mask" "F.Paste")
			(roundrect_rratio 0.25)
			(net 187 "VDD1")
			(pintype "passive")
		)
		(pad "2" smd roundrect
			(at 0.485 0 90)
			(size 0.59 0.64)
			(layers "F.Cu" "F.Mask" "F.Paste")
			(roundrect_rratio 0.25)
			(net 246 "SDA")
			(pintype "passive")
		)
	)
	(footprint "antmicro-footprints:R_0402_1005Metric"
		(layer "F.Cu")
		(at 126.555 89.72 -90)
		(descr "Resistor SMD 0402")
		(tags "resistor SMD 0402")
		(property "Reference" "R14"
			(at 1.03 0.58 270)
			(layer "F.SilkS")
			(effects
				(font
					(size 0.7 0.7)
					(thickness 0.15)
				)
				(justify left bottom)
			)
		)
		(property "Value" "R_10k_0402"
			(at 0 1.4 270)
			(layer "F.Fab")
			(effects
				(font
					(size 0.7 0.7)
					(thickness 0.15)
				)
				(justify left bottom)
			)
		)
		(property "Description" "10k resistor in 0402 package with 1% tolerance"
			(at 0 0 270)
			(layer "F.Fab")
			(hide yes)
			(effects
				(font
					(size 1.27 1.27)
					(thickness 0.15)
				)
			)
		)
		(property "Author" "Antmicro"
			(at 36.835 216.275 0)
			(layer "F.Fab")
			(hide yes)
			(effects
				(font
					(size 1 1)
					(thickness 0.15)
				)
			)
		)
		(property "License" "Apache-2.0"
			(at 36.835 216.275 0)
			(layer "F.Fab")
			(hide yes)
			(effects
				(font
					(size 1 1)
					(thickness 0.15)
				)
			)
		)
		(property "MPN" "CRCW040210K0FKEDHP"
			(at 36.835 216.275 0)
			(layer "F.Fab")
			(hide yes)
			(effects
				(font
					(size 1 1)
					(thickness 0.15)
				)
			)
		)
		(property "Manufacturer" "VISHAY"
			(at 36.835 216.275 0)
			(layer "F.Fab")
			(hide yes)
			(effects
				(font
					(size 1 1)
					(thickness 0.15)
				)
			)
		)
		(property "Tolerance" "1%"
			(at 36.835 216.275 0)
			(layer "F.Fab")
			(hide yes)
			(effects
				(font
					(size 1 1)
					(thickness 0.15)
				)
			)
		)
		(property "Val" "10k"
			(at 36.835 216.275 0)
			(layer "F.Fab")
			(hide yes)
			(effects
				(font
					(size 1 1)
					(thickness 0.15)
				)
			)
		)
		(sheetname "EEPROM")
		(sheetfile "EEPROM.kicad_sch")
		(attr smd)
		(fp_rect
			(start -0.93 -0.47)
			(end 0.93 0.47)
			(stroke
				(width 0.05)
				(type solid)
			)
			(fill no)
			(layer "F.CrtYd")
		)
		(fp_rect
			(start -0.5 -0.25)
			(end 0.5 0.25)
			(stroke
				(width 0.15)
				(type solid)
			)
			(fill no)
			(layer "F.Fab")
		)
		(pad "1" smd roundrect
			(at -0.485 0 270)
			(size 0.59 0.64)
			(layers "F.Cu" "F.Mask" "F.Paste")
			(roundrect_rratio 0.25)
			(net 187 "VDD1")
			(pintype "passive")
		)
		(pad "2" smd roundrect
			(at 0.485 0 270)
			(size 0.59 0.64)
			(layers "F.Cu" "F.Mask" "F.Paste")
			(roundrect_rratio 0.25)
			(net 247 "SCL")
			(pintype "passive")
		)
	)
	(footprint "antmicro-footprints:R_0402_1005Metric"
		(layer "B.Cu")
		(at 151.775 83.1 90)
		(descr "Resistor SMD 0402")
		(tags "resistor SMD 0402")
		(property "Reference" "R3"
			(at -0.75 0.3 270)
			(layer "B.SilkS")
			(effects
				(font
					(size 0.7 0.7)
					(thickness 0.15)
				)
				(justify left bottom mirror)
			)
		)
		(property "Value" "R_10k_0402"
			(at 0 -1.4 270)
			(layer "B.Fab")
			(effects
				(font
					(size 0.7 0.7)
					(thickness 0.15)
				)
				(justify left bottom mirror)
			)
		)
		(property "Description" "10k resistor in 0402 package with 1% tolerance"
			(at 0 0 90)
			(layer "F.Fab")
			(hide yes)
			(effects
				(font
					(size 1.27 1.27)
					(thickness 0.15)
				)
			)
		)
		(property "Author" "Antmicro"
			(at 234.875 -68.675 0)
			(layer "B.Fab")
			(hide yes)
			(effects
				(font
					(size 1 1)
					(thickness 0.15)
				)
				(justify mirror)
			)
		)
		(property "License" "Apache-2.0"
			(at 234.875 -68.675 0)
			(layer "B.Fab")
			(hide yes)
			(effects
				(font
					(size 1 1)
					(thickness 0.15)
				)
				(justify mirror)
			)
		)
		(property "MPN" "CRCW040210K0FKEDHP"
			(at 234.875 -68.675 0)
			(layer "B.Fab")
			(hide yes)
			(effects
				(font
					(size 1 1)
					(thickness 0.15)
				)
				(justify mirror)
			)
		)
		(property "Manufacturer" "VISHAY"
			(at 234.875 -68.675 0)
			(layer "B.Fab")
			(hide yes)
			(effects
				(font
					(size 1 1)
					(thickness 0.15)
				)
				(justify mirror)
			)
		)
		(property "Tolerance" "1%"
			(at 234.875 -68.675 0)
			(layer "B.Fab")
			(hide yes)
			(effects
				(font
					(size 1 1)
					(thickness 0.15)
				)
				(justify mirror)
			)
		)
		(property "Val" "10k"
			(at 234.875 -68.675 0)
			(layer "B.Fab")
			(hide yes)
			(effects
				(font
					(size 1 1)
					(thickness 0.15)
				)
				(justify mirror)
			)
		)
		(sheetname "LPDDR4")
		(sheetfile "lpddr4.kicad_sch")
		(attr smd)
		(fp_rect
			(start -0.93 0.47)
			(end 0.93 -0.47)
			(stroke
				(width 0.05)
				(type solid)
			)
			(fill no)
			(layer "B.CrtYd")
		)
		(fp_rect
			(start -0.5 0.25)
			(end 0.5 -0.25)
			(stroke
				(width 0.15)
				(type solid)
			)
			(fill no)
			(layer "B.Fab")
		)
		(pad "1" smd roundrect
			(at -0.485 0 90)
			(size 0.59 0.64)
			(layers "B.Cu" "B.Mask" "B.Paste")
			(roundrect_rratio 0.25)
			(net 222 "CS0_B")
			(pintype "passive")
		)
		(pad "2" smd roundrect
			(at 0.485 0 90)
			(size 0.59 0.64)
			(layers "B.Cu" "B.Mask" "B.Paste")
			(roundrect_rratio 0.25)
			(net 36 "GND")
			(pintype "passive")
		)
	)
	(footprint "antmicro-footprints:C_0201"
		(layer "B.Cu")
		(at 149.375 79.95 -90)
		(descr "Capacitor SMD 0201")
		(tags "capacitor SMD 0201")
		(property "Reference" "C2"
			(at -0.8 0.4 90)
			(layer "B.SilkS")
			(effects
				(font
					(size 0.7 0.7)
					(thickness 0.15)
				)
				(justify left bottom mirror)
			)
		)
		(property "Value" "C_100n_0201"
			(at 0 -1.4 90)
			(layer "B.Fab")
			(effects
				(font
					(size 0.7 0.7)
					(thickness 0.15)
				)
				(justify left bottom mirror)
			)
		)
		(property "Description" " "
			(at 0 0 270)
			(layer "F.Fab")
			(hide yes)
			(effects
				(font
					(size 1.27 1.27)
					(thickness 0.15)
				)
			)
		)
		(property "Author" "Antmicro"
			(at 69.425 229.325 0)
			(layer "B.Fab")
			(hide yes)
			(effects
				(font
					(size 1 1)
					(thickness 0.15)
				)
				(justify mirror)
			)
		)
		(property "Dielectric" ""
			(at 69.425 229.325 0)
			(layer "B.Fab")
			(hide yes)
			(effects
				(font
					(size 1 1)
					(thickness 0.15)
				)
				(justify mirror)
			)
		)
		(property "License" "Apache-2.0"
			(at 69.425 229.325 0)
			(layer "B.Fab")
			(hide yes)
			(effects
				(font
					(size 1 1)
					(thickness 0.15)
				)
				(justify mirror)
			)
		)
		(property "MPN" "CC0201KRX6S5BB104"
			(at 69.425 229.325 0)
			(layer "B.Fab")
			(hide yes)
			(effects
				(font
					(size 1 1)
					(thickness 0.15)
				)
				(justify mirror)
			)
		)
		(property "Manufacturer" "YAGEO"
			(at 69.425 229.325 0)
			(layer "B.Fab")
			(hide yes)
			(effects
				(font
					(size 1 1)
					(thickness 0.15)
				)
				(justify mirror)
			)
		)
		(property "Val" "100n"
			(at 69.425 229.325 0)
			(layer "B.Fab")
			(hide yes)
			(effects
				(font
					(size 1 1)
					(thickness 0.15)
				)
				(justify mirror)
			)
		)
		(property "Voltage" ""
			(at 69.425 229.325 0)
			(layer "B.Fab")
			(hide yes)
			(effects
				(font
					(size 1 1)
					(thickness 0.15)
				)
				(justify mirror)
			)
		)
		(sheetname "LPDDR4")
		(sheetfile "lpddr4.kicad_sch")
		(attr smd)
		(fp_rect
			(start -0.72 0.38)
			(end 0.72 -0.38)
			(stroke
				(width 0.05)
				(type solid)
			)
			(fill no)
			(layer "B.CrtYd")
		)
		(fp_rect
			(start 0.3 -0.15)
			(end -0.301 0.149)
			(stroke
				(width 0.15)
				(type solid)
			)
			(fill no)
			(layer "B.Fab")
		)
		(pad "" smd roundrect
			(at -0.349 0.002 270)
			(size 0.318 0.36)
			(layers "B.Paste")
			(roundrect_rratio 0.25)
		)
		(pad "" smd roundrect
			(at 0.341 0.002 270)
			(size 0.318 0.36)
			(layers "B.Paste")
			(roundrect_rratio 0.25)
		)
		(pad "1" smd roundrect
			(at -0.321 0.002 270)
			(size 0.46 0.4)
			(layers "B.Cu" "B.Mask")
			(roundrect_rratio 0.25)
			(net 36 "GND")
			(pintype "passive")
		)
		(pad "2" smd roundrect
			(at 0.32 0.002 270)
			(size 0.46 0.4)
			(layers "B.Cu" "B.Mask")
			(roundrect_rratio 0.25)
			(net 189 "VDDQ")
			(pintype "passive")
		)
	)
	(footprint "antmicro-footprints:C_0201"
		(layer "B.Cu")
		(at 146.975 81.3 90)
		(descr "Capacitor SMD 0201")
		(tags "capacitor SMD 0201")
		(property "Reference" "C4"
			(at -0.65 -0.4 90)
			(layer "B.SilkS")
			(effects
				(font
					(size 0.7 0.7)
					(thickness 0.15)
				)
				(justify right bottom mirror)
			)
		)
		(property "Value" "C_100n_0201"
			(at 0 -1.4 90)
			(layer "B.Fab")
			(effects
				(font
					(size 0.7 0.7)
					(thickness 0.15)
				)
				(justify right bottom mirror)
			)
		)
		(property "Description" " "
			(at 0 0 90)
			(layer "F.Fab")
			(hide yes)
			(effects
				(font
					(size 1.27 1.27)
					(thickness 0.15)
				)
			)
		)
		(property "Author" "Antmicro"
			(at 228.275 -65.675 0)
			(layer "B.Fab")
			(hide yes)
			(effects
				(font
					(size 1 1)
					(thickness 0.15)
				)
				(justify mirror)
			)
		)
		(property "Dielectric" ""
			(at 228.275 -65.675 0)
			(layer "B.Fab")
			(hide yes)
			(effects
				(font
					(size 1 1)
					(thickness 0.15)
				)
				(justify mirror)
			)
		)
		(property "License" "Apache-2.0"
			(at 228.275 -65.675 0)
			(layer "B.Fab")
			(hide yes)
			(effects
				(font
					(size 1 1)
					(thickness 0.15)
				)
				(justify mirror)
			)
		)
		(property "MPN" "CC0201KRX6S5BB104"
			(at 228.275 -65.675 0)
			(layer "B.Fab")
			(hide yes)
			(effects
				(font
					(size 1 1)
					(thickness 0.15)
				)
				(justify mirror)
			)
		)
		(property "Manufacturer" "YAGEO"
			(at 228.275 -65.675 0)
			(layer "B.Fab")
			(hide yes)
			(effects
				(font
					(size 1 1)
					(thickness 0.15)
				)
				(justify mirror)
			)
		)
		(property "Val" "100n"
			(at 228.275 -65.675 0)
			(layer "B.Fab")
			(hide yes)
			(effects
				(font
					(size 1 1)
					(thickness 0.15)
				)
				(justify mirror)
			)
		)
		(property "Voltage" ""
			(at 228.275 -65.675 0)
			(layer "B.Fab")
			(hide yes)
			(effects
				(font
					(size 1 1)
					(thickness 0.15)
				)
				(justify mirror)
			)
		)
		(sheetname "LPDDR4")
		(sheetfile "lpddr4.kicad_sch")
		(attr smd)
		(fp_rect
			(start -0.72 0.38)
			(end 0.72 -0.38)
			(stroke
				(width 0.05)
				(type solid)
			)
			(fill no)
			(layer "B.CrtYd")
		)
		(fp_rect
			(start 0.3 -0.15)
			(end -0.301 0.149)
			(stroke
				(width 0.15)
				(type solid)
			)
			(fill no)
			(layer "B.Fab")
		)
		(pad "" smd roundrect
			(at -0.349 0.002 90)
			(size 0.318 0.36)
			(layers "B.Paste")
			(roundrect_rratio 0.25)
		)
		(pad "" smd roundrect
			(at 0.341 0.002 90)
			(size 0.318 0.36)
			(layers "B.Paste")
			(roundrect_rratio 0.25)
		)
		(pad "1" smd roundrect
			(at -0.321 0.002 90)
			(size 0.46 0.4)
			(layers "B.Cu" "B.Mask")
			(roundrect_rratio 0.25)
			(net 36 "GND")
			(pintype "passive")
		)
		(pad "2" smd roundrect
			(at 0.32 0.002 90)
			(size 0.46 0.4)
			(layers "B.Cu" "B.Mask")
			(roundrect_rratio 0.25)
			(net 189 "VDDQ")
			(pintype "passive")
		)
	)
	(footprint "antmicro-footprints:C_0201"
		(locked yes)
		(layer "B.Cu")
		(at 146.803 92.01 -90)
		(descr "Capacitor SMD 0201")
		(tags "capacitor SMD 0201")
		(property "Reference" "C7"
			(at 0.54 -0.372 90)
			(layer "B.SilkS")
			(effects
				(font
					(size 0.7 0.7)
					(thickness 0.15)
				)
				(justify left bottom mirror)
			)
		)
		(property "Value" "C_100n_0201"
			(at 0 -1.4 90)
			(layer "B.Fab")
			(effects
				(font
					(size 0.7 0.7)
					(thickness 0.15)
				)
				(justify left bottom mirror)
			)
		)
		(property "Description" " "
			(at 0 0 270)
			(layer "F.Fab")
			(hide yes)
			(effects
				(font
					(size 1.27 1.27)
					(thickness 0.15)
				)
			)
		)
		(property "Author" "Antmicro"
			(at 54.793 238.813 0)
			(layer "B.Fab")
			(hide yes)
			(effects
				(font
					(size 1 1)
					(thickness 0.15)
				)
				(justify mirror)
			)
		)
		(property "Dielectric" ""
			(at 54.793 238.813 0)
			(layer "B.Fab")
			(hide yes)
			(effects
				(font
					(size 1 1)
					(thickness 0.15)
				)
				(justify mirror)
			)
		)
		(property "License" "Apache-2.0"
			(at 54.793 238.813 0)
			(layer "B.Fab")
			(hide yes)
			(effects
				(font
					(size 1 1)
					(thickness 0.15)
				)
				(justify mirror)
			)
		)
		(property "MPN" "CC0201KRX6S5BB104"
			(at 54.793 238.813 0)
			(layer "B.Fab")
			(hide yes)
			(effects
				(font
					(size 1 1)
					(thickness 0.15)
				)
				(justify mirror)
			)
		)
		(property "Manufacturer" "YAGEO"
			(at 54.793 238.813 0)
			(layer "B.Fab")
			(hide yes)
			(effects
				(font
					(size 1 1)
					(thickness 0.15)
				)
				(justify mirror)
			)
		)
		(property "Val" "100n"
			(at 54.793 238.813 0)
			(layer "B.Fab")
			(hide yes)
			(effects
				(font
					(size 1 1)
					(thickness 0.15)
				)
				(justify mirror)
			)
		)
		(property "Voltage" ""
			(at 54.793 238.813 0)
			(layer "B.Fab")
			(hide yes)
			(effects
				(font
					(size 1 1)
					(thickness 0.15)
				)
				(justify mirror)
			)
		)
		(sheetname "LPDDR4")
		(sheetfile "lpddr4.kicad_sch")
		(attr smd)
		(fp_rect
			(start -0.72 0.38)
			(end 0.72 -0.38)
			(stroke
				(width 0.05)
				(type solid)
			)
			(fill no)
			(layer "B.CrtYd")
		)
		(fp_rect
			(start 0.3 -0.15)
			(end -0.301 0.149)
			(stroke
				(width 0.15)
				(type solid)
			)
			(fill no)
			(layer "B.Fab")
		)
		(pad "" smd roundrect
			(at -0.349 0.002 270)
			(size 0.318 0.36)
			(layers "B.Paste")
			(roundrect_rratio 0.25)
		)
		(pad "" smd roundrect
			(at 0.341 0.002 270)
			(size 0.318 0.36)
			(layers "B.Paste")
			(roundrect_rratio 0.25)
		)
		(pad "1" smd roundrect
			(at -0.321 0.002 270)
			(size 0.46 0.4)
			(layers "B.Cu" "B.Mask")
			(roundrect_rratio 0.25)
			(net 36 "GND")
			(pintype "passive")
		)
		(pad "2" smd roundrect
			(at 0.32 0.002 270)
			(size 0.46 0.4)
			(layers "B.Cu" "B.Mask")
			(roundrect_rratio 0.25)
			(net 189 "VDDQ")
			(pintype "passive")
		)
	)
	(footprint "antmicro-footprints:C_0201"
		(layer "B.Cu")
		(at 151.375 86.15)
		(descr "Capacitor SMD 0201")
		(tags "capacitor SMD 0201")
		(property "Reference" "C12"
			(at -1.3 1.2 0)
			(layer "B.SilkS")
			(effects
				(font
					(size 0.7 0.7)
					(thickness 0.15)
				)
				(justify right bottom mirror)
			)
		)
		(property "Value" "C_100n_0201"
			(at 0 -1.4 0)
			(layer "B.Fab")
			(effects
				(font
					(size 0.7 0.7)
					(thickness 0.15)
				)
				(justify right bottom mirror)
			)
		)
		(property "Description" " "
			(at 0 0 0)
			(layer "F.Fab")
			(hide yes)
			(effects
				(font
					(size 1.27 1.27)
					(thickness 0.15)
				)
			)
		)
		(property "Author" "Antmicro"
			(at 0 0 0)
			(layer "B.Fab")
			(hide yes)
			(effects
				(font
					(size 1 1)
					(thickness 0.15)
				)
				(justify mirror)
			)
		)
		(property "Dielectric" ""
			(at 0 0 0)
			(layer "B.Fab")
			(hide yes)
			(effects
				(font
					(size 1 1)
					(thickness 0.15)
				)
				(justify mirror)
			)
		)
		(property "License" "Apache-2.0"
			(at 0 0 0)
			(layer "B.Fab")
			(hide yes)
			(effects
				(font
					(size 1 1)
					(thickness 0.15)
				)
				(justify mirror)
			)
		)
		(property "MPN" "CC0201KRX6S5BB104"
			(at 0 0 0)
			(layer "B.Fab")
			(hide yes)
			(effects
				(font
					(size 1 1)
					(thickness 0.15)
				)
				(justify mirror)
			)
		)
		(property "Manufacturer" "YAGEO"
			(at 0 0 0)
			(layer "B.Fab")
			(hide yes)
			(effects
				(font
					(size 1 1)
					(thickness 0.15)
				)
				(justify mirror)
			)
		)
		(property "Val" "100n"
			(at 0 0 0)
			(layer "B.Fab")
			(hide yes)
			(effects
				(font
					(size 1 1)
					(thickness 0.15)
				)
				(justify mirror)
			)
		)
		(property "Voltage" ""
			(at 0 0 0)
			(layer "B.Fab")
			(hide yes)
			(effects
				(font
					(size 1 1)
					(thickness 0.15)
				)
				(justify mirror)
			)
		)
		(sheetname "LPDDR4")
		(sheetfile "lpddr4.kicad_sch")
		(attr smd)
		(fp_rect
			(start -0.72 0.38)
			(end 0.72 -0.38)
			(stroke
				(width 0.05)
				(type solid)
			)
			(fill no)
			(layer "B.CrtYd")
		)
		(fp_rect
			(start 0.3 -0.15)
			(end -0.301 0.149)
			(stroke
				(width 0.15)
				(type solid)
			)
			(fill no)
			(layer "B.Fab")
		)
		(pad "" smd roundrect
			(at -0.349 0.002)
			(size 0.318 0.36)
			(layers "B.Paste")
			(roundrect_rratio 0.25)
		)
		(pad "" smd roundrect
			(at 0.341 0.002)
			(size 0.318 0.36)
			(layers "B.Paste")
			(roundrect_rratio 0.25)
		)
		(pad "1" smd roundrect
			(at -0.321 0.002)
			(size 0.46 0.4)
			(layers "B.Cu" "B.Mask")
			(roundrect_rratio 0.25)
			(net 36 "GND")
			(pintype "passive")
		)
		(pad "2" smd roundrect
			(at 0.32 0.002)
			(size 0.46 0.4)
			(layers "B.Cu" "B.Mask")
			(roundrect_rratio 0.25)
			(net 188 "VDD2")
			(pintype "passive")
		)
	)
	(footprint "antmicro-footprints:C_0201"
		(layer "B.Cu")
		(at 152.575 81.4 90)
		(descr "Capacitor SMD 0201")
		(tags "capacitor SMD 0201")
		(property "Reference" "C13"
			(at 0.65 0.3 90)
			(layer "B.SilkS")
			(effects
				(font
					(size 0.7 0.7)
					(thickness 0.15)
				)
				(justify right bottom mirror)
			)
		)
		(property "Value" "C_100n_0201"
			(at 0 -1.4 90)
			(layer "B.Fab")
			(effects
				(font
					(size 0.7 0.7)
					(thickness 0.15)
				)
				(justify right bottom mirror)
			)
		)
		(property "Description" " "
			(at 0 0 90)
			(layer "F.Fab")
			(hide yes)
			(effects
				(font
					(size 1.27 1.27)
					(thickness 0.15)
				)
			)
		)
		(property "Author" "Antmicro"
			(at 233.975 -71.175 0)
			(layer "B.Fab")
			(hide yes)
			(effects
				(font
					(size 1 1)
					(thickness 0.15)
				)
				(justify mirror)
			)
		)
		(property "Dielectric" ""
			(at 233.975 -71.175 0)
			(layer "B.Fab")
			(hide yes)
			(effects
				(font
					(size 1 1)
					(thickness 0.15)
				)
				(justify mirror)
			)
		)
		(property "License" "Apache-2.0"
			(at 233.975 -71.175 0)
			(layer "B.Fab")
			(hide yes)
			(effects
				(font
					(size 1 1)
					(thickness 0.15)
				)
				(justify mirror)
			)
		)
		(property "MPN" "CC0201KRX6S5BB104"
			(at 233.975 -71.175 0)
			(layer "B.Fab")
			(hide yes)
			(effects
				(font
					(size 1 1)
					(thickness 0.15)
				)
				(justify mirror)
			)
		)
		(property "Manufacturer" "YAGEO"
			(at 233.975 -71.175 0)
			(layer "B.Fab")
			(hide yes)
			(effects
				(font
					(size 1 1)
					(thickness 0.15)
				)
				(justify mirror)
			)
		)
		(property "Val" "100n"
			(at 233.975 -71.175 0)
			(layer "B.Fab")
			(hide yes)
			(effects
				(font
					(size 1 1)
					(thickness 0.15)
				)
				(justify mirror)
			)
		)
		(property "Voltage" ""
			(at 233.975 -71.175 0)
			(layer "B.Fab")
			(hide yes)
			(effects
				(font
					(size 1 1)
					(thickness 0.15)
				)
				(justify mirror)
			)
		)
		(sheetname "LPDDR4")
		(sheetfile "lpddr4.kicad_sch")
		(attr smd)
		(fp_rect
			(start -0.72 0.38)
			(end 0.72 -0.38)
			(stroke
				(width 0.05)
				(type solid)
			)
			(fill no)
			(layer "B.CrtYd")
		)
		(fp_rect
			(start 0.3 -0.15)
			(end -0.301 0.149)
			(stroke
				(width 0.15)
				(type solid)
			)
			(fill no)
			(layer "B.Fab")
		)
		(pad "" smd roundrect
			(at -0.349 0.002 90)
			(size 0.318 0.36)
			(layers "B.Paste")
			(roundrect_rratio 0.25)
		)
		(pad "" smd roundrect
			(at 0.341 0.002 90)
			(size 0.318 0.36)
			(layers "B.Paste")
			(roundrect_rratio 0.25)
		)
		(pad "1" smd roundrect
			(at -0.321 0.002 90)
			(size 0.46 0.4)
			(layers "B.Cu" "B.Mask")
			(roundrect_rratio 0.25)
			(net 36 "GND")
			(pintype "passive")
		)
		(pad "2" smd roundrect
			(at 0.32 0.002 90)
			(size 0.46 0.4)
			(layers "B.Cu" "B.Mask")
			(roundrect_rratio 0.25)
			(net 189 "VDDQ")
			(pintype "passive")
		)
	)
	(footprint "antmicro-footprints:C_0201"
		(layer "B.Cu")
		(at 153.375 82.55 -90)
		(descr "Capacitor SMD 0201")
		(tags "capacitor SMD 0201")
		(property "Reference" "C8"
			(at 0.6 -0.3 90)
			(layer "B.SilkS")
			(effects
				(font
					(size 0.7 0.7)
					(thickness 0.15)
				)
				(justify left bottom mirror)
			)
		)
		(property "Value" "C_100n_0201"
			(at 0 -1.4 90)
			(layer "B.Fab")
			(effects
				(font
					(size 0.7 0.7)
					(thickness 0.15)
				)
				(justify left bottom mirror)
			)
		)
		(property "Description" " "
			(at 0 0 270)
			(layer "F.Fab")
			(hide yes)
			(effects
				(font
					(size 1.27 1.27)
					(thickness 0.15)
				)
			)
		)
		(property "Author" "Antmicro"
			(at 70.825 235.925 0)
			(layer "B.Fab")
			(hide yes)
			(effects
				(font
					(size 1 1)
					(thickness 0.15)
				)
				(justify mirror)
			)
		)
		(property "Dielectric" ""
			(at 70.825 235.925 0)
			(layer "B.Fab")
			(hide yes)
			(effects
				(font
					(size 1 1)
					(thickness 0.15)
				)
				(justify mirror)
			)
		)
		(property "License" "Apache-2.0"
			(at 70.825 235.925 0)
			(layer "B.Fab")
			(hide yes)
			(effects
				(font
					(size 1 1)
					(thickness 0.15)
				)
				(justify mirror)
			)
		)
		(property "MPN" "CC0201KRX6S5BB104"
			(at 70.825 235.925 0)
			(layer "B.Fab")
			(hide yes)
			(effects
				(font
					(size 1 1)
					(thickness 0.15)
				)
				(justify mirror)
			)
		)
		(property "Manufacturer" "YAGEO"
			(at 70.825 235.925 0)
			(layer "B.Fab")
			(hide yes)
			(effects
				(font
					(size 1 1)
					(thickness 0.15)
				)
				(justify mirror)
			)
		)
		(property "Val" "100n"
			(at 70.825 235.925 0)
			(layer "B.Fab")
			(hide yes)
			(effects
				(font
					(size 1 1)
					(thickness 0.15)
				)
				(justify mirror)
			)
		)
		(property "Voltage" ""
			(at 70.825 235.925 0)
			(layer "B.Fab")
			(hide yes)
			(effects
				(font
					(size 1 1)
					(thickness 0.15)
				)
				(justify mirror)
			)
		)
		(sheetname "LPDDR4")
		(sheetfile "lpddr4.kicad_sch")
		(attr smd)
		(fp_rect
			(start -0.72 0.38)
			(end 0.72 -0.38)
			(stroke
				(width 0.05)
				(type solid)
			)
			(fill no)
			(layer "B.CrtYd")
		)
		(fp_rect
			(start 0.3 -0.15)
			(end -0.301 0.149)
			(stroke
				(width 0.15)
				(type solid)
			)
			(fill no)
			(layer "B.Fab")
		)
		(pad "" smd roundrect
			(at -0.349 0.002 270)
			(size 0.318 0.36)
			(layers "B.Paste")
			(roundrect_rratio 0.25)
		)
		(pad "" smd roundrect
			(at 0.341 0.002 270)
			(size 0.318 0.36)
			(layers "B.Paste")
			(roundrect_rratio 0.25)
		)
		(pad "1" smd roundrect
			(at -0.321 0.002 270)
			(size 0.46 0.4)
			(layers "B.Cu" "B.Mask")
			(roundrect_rratio 0.25)
			(net 36 "GND")
			(pintype "passive")
		)
		(pad "2" smd roundrect
			(at 0.32 0.002 270)
			(size 0.46 0.4)
			(layers "B.Cu" "B.Mask")
			(roundrect_rratio 0.25)
			(net 189 "VDDQ")
			(pintype "passive")
		)
	)
	(footprint "antmicro-footprints:C_0201"
		(layer "B.Cu")
		(at 149.375 91 -90)
		(descr "Capacitor SMD 0201")
		(tags "capacitor SMD 0201")
		(property "Reference" "C5"
			(at -0.75 0.4 90)
			(layer "B.SilkS")
			(effects
				(font
					(size 0.7 0.7)
					(thickness 0.15)
				)
				(justify left bottom mirror)
			)
		)
		(property "Value" "C_100n_0201"
			(at 0 -1.4 90)
			(layer "B.Fab")
			(effects
				(font
					(size 0.7 0.7)
					(thickness 0.15)
				)
				(justify left bottom mirror)
			)
		)
		(property "Description" " "
			(at 0 0 270)
			(layer "F.Fab")
			(hide yes)
			(effects
				(font
					(size 1.27 1.27)
					(thickness 0.15)
				)
			)
		)
		(property "Author" "Antmicro"
			(at 58.375 240.375 0)
			(layer "B.Fab")
			(hide yes)
			(effects
				(font
					(size 1 1)
					(thickness 0.15)
				)
				(justify mirror)
			)
		)
		(property "Dielectric" ""
			(at 58.375 240.375 0)
			(layer "B.Fab")
			(hide yes)
			(effects
				(font
					(size 1 1)
					(thickness 0.15)
				)
				(justify mirror)
			)
		)
		(property "License" "Apache-2.0"
			(at 58.375 240.375 0)
			(layer "B.Fab")
			(hide yes)
			(effects
				(font
					(size 1 1)
					(thickness 0.15)
				)
				(justify mirror)
			)
		)
		(property "MPN" "CC0201KRX6S5BB104"
			(at 58.375 240.375 0)
			(layer "B.Fab")
			(hide yes)
			(effects
				(font
					(size 1 1)
					(thickness 0.15)
				)
				(justify mirror)
			)
		)
		(property "Manufacturer" "YAGEO"
			(at 58.375 240.375 0)
			(layer "B.Fab")
			(hide yes)
			(effects
				(font
					(size 1 1)
					(thickness 0.15)
				)
				(justify mirror)
			)
		)
		(property "Val" "100n"
			(at 58.375 240.375 0)
			(layer "B.Fab")
			(hide yes)
			(effects
				(font
					(size 1 1)
					(thickness 0.15)
				)
				(justify mirror)
			)
		)
		(property "Voltage" ""
			(at 58.375 240.375 0)
			(layer "B.Fab")
			(hide yes)
			(effects
				(font
					(size 1 1)
					(thickness 0.15)
				)
				(justify mirror)
			)
		)
		(sheetname "LPDDR4")
		(sheetfile "lpddr4.kicad_sch")
		(attr smd)
		(fp_rect
			(start -0.72 0.38)
			(end 0.72 -0.38)
			(stroke
				(width 0.05)
				(type solid)
			)
			(fill no)
			(layer "B.CrtYd")
		)
		(fp_rect
			(start 0.3 -0.15)
			(end -0.301 0.149)
			(stroke
				(width 0.15)
				(type solid)
			)
			(fill no)
			(layer "B.Fab")
		)
		(pad "" smd roundrect
			(at -0.349 0.002 270)
			(size 0.318 0.36)
			(layers "B.Paste")
			(roundrect_rratio 0.25)
		)
		(pad "" smd roundrect
			(at 0.341 0.002 270)
			(size 0.318 0.36)
			(layers "B.Paste")
			(roundrect_rratio 0.25)
		)
		(pad "1" smd roundrect
			(at -0.321 0.002 270)
			(size 0.46 0.4)
			(layers "B.Cu" "B.Mask")
			(roundrect_rratio 0.25)
			(net 36 "GND")
			(pintype "passive")
		)
		(pad "2" smd roundrect
			(at 0.32 0.002 270)
			(size 0.46 0.4)
			(layers "B.Cu" "B.Mask")
			(roundrect_rratio 0.25)
			(net 189 "VDDQ")
			(pintype "passive")
		)
	)
	(footprint "antmicro-footprints:C_0201"
		(layer "B.Cu")
		(at 149.375 81.45 -90)
		(descr "Capacitor SMD 0201")
		(tags "capacitor SMD 0201")
		(property "Reference" "C16"
			(at -1.2 -1.2 90)
			(layer "B.SilkS")
			(effects
				(font
					(size 0.7 0.7)
					(thickness 0.15)
				)
				(justify left bottom mirror)
			)
		)
		(property "Value" "C_100n_0201"
			(at 0 -1.4 90)
			(layer "B.Fab")
			(effects
				(font
					(size 0.7 0.7)
					(thickness 0.15)
				)
				(justify left bottom mirror)
			)
		)
		(property "Description" " "
			(at 0 0 270)
			(layer "F.Fab")
			(hide yes)
			(effects
				(font
					(size 1.27 1.27)
					(thickness 0.15)
				)
			)
		)
		(property "Author" "Antmicro"
			(at 67.925 230.825 0)
			(layer "B.Fab")
			(hide yes)
			(effects
				(font
					(size 1 1)
					(thickness 0.15)
				)
				(justify mirror)
			)
		)
		(property "Dielectric" ""
			(at 67.925 230.825 0)
			(layer "B.Fab")
			(hide yes)
			(effects
				(font
					(size 1 1)
					(thickness 0.15)
				)
				(justify mirror)
			)
		)
		(property "License" "Apache-2.0"
			(at 67.925 230.825 0)
			(layer "B.Fab")
			(hide yes)
			(effects
				(font
					(size 1 1)
					(thickness 0.15)
				)
				(justify mirror)
			)
		)
		(property "MPN" "CC0201KRX6S5BB104"
			(at 67.925 230.825 0)
			(layer "B.Fab")
			(hide yes)
			(effects
				(font
					(size 1 1)
					(thickness 0.15)
				)
				(justify mirror)
			)
		)
		(property "Manufacturer" "YAGEO"
			(at 67.925 230.825 0)
			(layer "B.Fab")
			(hide yes)
			(effects
				(font
					(size 1 1)
					(thickness 0.15)
				)
				(justify mirror)
			)
		)
		(property "Val" "100n"
			(at 67.925 230.825 0)
			(layer "B.Fab")
			(hide yes)
			(effects
				(font
					(size 1 1)
					(thickness 0.15)
				)
				(justify mirror)
			)
		)
		(property "Voltage" ""
			(at 67.925 230.825 0)
			(layer "B.Fab")
			(hide yes)
			(effects
				(font
					(size 1 1)
					(thickness 0.15)
				)
				(justify mirror)
			)
		)
		(sheetname "LPDDR4")
		(sheetfile "lpddr4.kicad_sch")
		(attr smd)
		(fp_rect
			(start -0.72 0.38)
			(end 0.72 -0.38)
			(stroke
				(width 0.05)
				(type solid)
			)
			(fill no)
			(layer "B.CrtYd")
		)
		(fp_rect
			(start 0.3 -0.15)
			(end -0.301 0.149)
			(stroke
				(width 0.15)
				(type solid)
			)
			(fill no)
			(layer "B.Fab")
		)
		(pad "" smd roundrect
			(at -0.349 0.002 270)
			(size 0.318 0.36)
			(layers "B.Paste")
			(roundrect_rratio 0.25)
		)
		(pad "" smd roundrect
			(at 0.341 0.002 270)
			(size 0.318 0.36)
			(layers "B.Paste")
			(roundrect_rratio 0.25)
		)
		(pad "1" smd roundrect
			(at -0.321 0.002 270)
			(size 0.46 0.4)
			(layers "B.Cu" "B.Mask")
			(roundrect_rratio 0.25)
			(net 36 "GND")
			(pintype "passive")
		)
		(pad "2" smd roundrect
			(at 0.32 0.002 270)
			(size 0.46 0.4)
			(layers "B.Cu" "B.Mask")
			(roundrect_rratio 0.25)
			(net 189 "VDDQ")
			(pintype "passive")
		)
	)
	(footprint "antmicro-footprints:C_0201"
		(layer "B.Cu")
		(at 149.375 92.5 -90)
		(descr "Capacitor SMD 0201")
		(tags "capacitor SMD 0201")
		(property "Reference" "C17"
			(at -0.85 -1.3 90)
			(layer "B.SilkS")
			(effects
				(font
					(size 0.7 0.7)
					(thickness 0.15)
				)
				(justify left bottom mirror)
			)
		)
		(property "Value" "C_100n_0201"
			(at 0 -1.4 90)
			(layer "B.Fab")
			(effects
				(font
					(size 0.7 0.7)
					(thickness 0.15)
				)
				(justify left bottom mirror)
			)
		)
		(property "Description" " "
			(at 0 0 270)
			(layer "F.Fab")
			(hide yes)
			(effects
				(font
					(size 1.27 1.27)
					(thickness 0.15)
				)
			)
		)
		(property "Author" "Antmicro"
			(at 56.875 241.875 0)
			(layer "B.Fab")
			(hide yes)
			(effects
				(font
					(size 1 1)
					(thickness 0.15)
				)
				(justify mirror)
			)
		)
		(property "Dielectric" ""
			(at 56.875 241.875 0)
			(layer "B.Fab")
			(hide yes)
			(effects
				(font
					(size 1 1)
					(thickness 0.15)
				)
				(justify mirror)
			)
		)
		(property "License" "Apache-2.0"
			(at 56.875 241.875 0)
			(layer "B.Fab")
			(hide yes)
			(effects
				(font
					(size 1 1)
					(thickness 0.15)
				)
				(justify mirror)
			)
		)
		(property "MPN" "CC0201KRX6S5BB104"
			(at 56.875 241.875 0)
			(layer "B.Fab")
			(hide yes)
			(effects
				(font
					(size 1 1)
					(thickness 0.15)
				)
				(justify mirror)
			)
		)
		(property "Manufacturer" "YAGEO"
			(at 56.875 241.875 0)
			(layer "B.Fab")
			(hide yes)
			(effects
				(font
					(size 1 1)
					(thickness 0.15)
				)
				(justify mirror)
			)
		)
		(property "Val" "100n"
			(at 56.875 241.875 0)
			(layer "B.Fab")
			(hide yes)
			(effects
				(font
					(size 1 1)
					(thickness 0.15)
				)
				(justify mirror)
			)
		)
		(property "Voltage" ""
			(at 56.875 241.875 0)
			(layer "B.Fab")
			(hide yes)
			(effects
				(font
					(size 1 1)
					(thickness 0.15)
				)
				(justify mirror)
			)
		)
		(sheetname "LPDDR4")
		(sheetfile "lpddr4.kicad_sch")
		(attr smd)
		(fp_rect
			(start -0.72 0.38)
			(end 0.72 -0.38)
			(stroke
				(width 0.05)
				(type solid)
			)
			(fill no)
			(layer "B.CrtYd")
		)
		(fp_rect
			(start 0.3 -0.15)
			(end -0.301 0.149)
			(stroke
				(width 0.15)
				(type solid)
			)
			(fill no)
			(layer "B.Fab")
		)
		(pad "" smd roundrect
			(at -0.349 0.002 270)
			(size 0.318 0.36)
			(layers "B.Paste")
			(roundrect_rratio 0.25)
		)
		(pad "" smd roundrect
			(at 0.341 0.002 270)
			(size 0.318 0.36)
			(layers "B.Paste")
			(roundrect_rratio 0.25)
		)
		(pad "1" smd roundrect
			(at -0.321 0.002 270)
			(size 0.46 0.4)
			(layers "B.Cu" "B.Mask")
			(roundrect_rratio 0.25)
			(net 36 "GND")
			(pintype "passive")
		)
		(pad "2" smd roundrect
			(at 0.32 0.002 270)
			(size 0.46 0.4)
			(layers "B.Cu" "B.Mask")
			(roundrect_rratio 0.25)
			(net 189 "VDDQ")
			(pintype "passive")
		)
	)
	(footprint "antmicro-footprints:C_0201"
		(layer "B.Cu")
		(at 146.325 83.15 90)
		(descr "Capacitor SMD 0201")
		(tags "capacitor SMD 0201")
		(property "Reference" "C19"
			(at -1.1 -0.45 90)
			(layer "B.SilkS")
			(effects
				(font
					(size 0.7 0.7)
					(thickness 0.15)
				)
				(justify right bottom mirror)
			)
		)
		(property "Value" "C_100n_0201"
			(at 0 -1.4 90)
			(layer "B.Fab")
			(effects
				(font
					(size 0.7 0.7)
					(thickness 0.15)
				)
				(justify right bottom mirror)
			)
		)
		(property "Description" " "
			(at 0 0 90)
			(layer "F.Fab")
			(hide yes)
			(effects
				(font
					(size 1.27 1.27)
					(thickness 0.15)
				)
			)
		)
		(property "Author" "Antmicro"
			(at 229.475 -63.175 0)
			(layer "B.Fab")
			(hide yes)
			(effects
				(font
					(size 1 1)
					(thickness 0.15)
				)
				(justify mirror)
			)
		)
		(property "Dielectric" ""
			(at 229.475 -63.175 0)
			(layer "B.Fab")
			(hide yes)
			(effects
				(font
					(size 1 1)
					(thickness 0.15)
				)
				(justify mirror)
			)
		)
		(property "License" "Apache-2.0"
			(at 229.475 -63.175 0)
			(layer "B.Fab")
			(hide yes)
			(effects
				(font
					(size 1 1)
					(thickness 0.15)
				)
				(justify mirror)
			)
		)
		(property "MPN" "CC0201KRX6S5BB104"
			(at 229.475 -63.175 0)
			(layer "B.Fab")
			(hide yes)
			(effects
				(font
					(size 1 1)
					(thickness 0.15)
				)
				(justify mirror)
			)
		)
		(property "Manufacturer" "YAGEO"
			(at 229.475 -63.175 0)
			(layer "B.Fab")
			(hide yes)
			(effects
				(font
					(size 1 1)
					(thickness 0.15)
				)
				(justify mirror)
			)
		)
		(property "Val" "100n"
			(at 229.475 -63.175 0)
			(layer "B.Fab")
			(hide yes)
			(effects
				(font
					(size 1 1)
					(thickness 0.15)
				)
				(justify mirror)
			)
		)
		(property "Voltage" ""
			(at 229.475 -63.175 0)
			(layer "B.Fab")
			(hide yes)
			(effects
				(font
					(size 1 1)
					(thickness 0.15)
				)
				(justify mirror)
			)
		)
		(sheetname "LPDDR4")
		(sheetfile "lpddr4.kicad_sch")
		(attr smd)
		(fp_rect
			(start -0.72 0.38)
			(end 0.72 -0.38)
			(stroke
				(width 0.05)
				(type solid)
			)
			(fill no)
			(layer "B.CrtYd")
		)
		(fp_rect
			(start 0.3 -0.15)
			(end -0.301 0.149)
			(stroke
				(width 0.15)
				(type solid)
			)
			(fill no)
			(layer "B.Fab")
		)
		(pad "" smd roundrect
			(at -0.349 0.002 90)
			(size 0.318 0.36)
			(layers "B.Paste")
			(roundrect_rratio 0.25)
		)
		(pad "" smd roundrect
			(at 0.341 0.002 90)
			(size 0.318 0.36)
			(layers "B.Paste")
			(roundrect_rratio 0.25)
		)
		(pad "1" smd roundrect
			(at -0.321 0.002 90)
			(size 0.46 0.4)
			(layers "B.Cu" "B.Mask")
			(roundrect_rratio 0.25)
			(net 36 "GND")
			(pintype "passive")
		)
		(pad "2" smd roundrect
			(at 0.32 0.002 90)
			(size 0.46 0.4)
			(layers "B.Cu" "B.Mask")
			(roundrect_rratio 0.25)
			(net 189 "VDDQ")
			(pintype "passive")
		)
	)
	(footprint "antmicro-footprints:C_0201"
		(layer "B.Cu")
		(at 149.375 87.65 -90)
		(descr "Capacitor SMD 0201")
		(tags "capacitor SMD 0201")
		(property "Reference" "C23"
			(at -0.9 0.5 90)
			(layer "B.SilkS")
			(effects
				(font
					(size 0.7 0.7)
					(thickness 0.15)
				)
				(justify left bottom mirror)
			)
		)
		(property "Value" "C_100n_0201"
			(at 0 -1.4 90)
			(layer "B.Fab")
			(effects
				(font
					(size 0.7 0.7)
					(thickness 0.15)
				)
				(justify left bottom mirror)
			)
		)
		(property "Description" " "
			(at 0 0 270)
			(layer "F.Fab")
			(hide yes)
			(effects
				(font
					(size 1.27 1.27)
					(thickness 0.15)
				)
			)
		)
		(property "Author" "Antmicro"
			(at 61.725 237.025 0)
			(layer "B.Fab")
			(hide yes)
			(effects
				(font
					(size 1 1)
					(thickness 0.15)
				)
				(justify mirror)
			)
		)
		(property "Dielectric" ""
			(at 61.725 237.025 0)
			(layer "B.Fab")
			(hide yes)
			(effects
				(font
					(size 1 1)
					(thickness 0.15)
				)
				(justify mirror)
			)
		)
		(property "License" "Apache-2.0"
			(at 61.725 237.025 0)
			(layer "B.Fab")
			(hide yes)
			(effects
				(font
					(size 1 1)
					(thickness 0.15)
				)
				(justify mirror)
			)
		)
		(property "MPN" "CC0201KRX6S5BB104"
			(at 61.725 237.025 0)
			(layer "B.Fab")
			(hide yes)
			(effects
				(font
					(size 1 1)
					(thickness 0.15)
				)
				(justify mirror)
			)
		)
		(property "Manufacturer" "YAGEO"
			(at 61.725 237.025 0)
			(layer "B.Fab")
			(hide yes)
			(effects
				(font
					(size 1 1)
					(thickness 0.15)
				)
				(justify mirror)
			)
		)
		(property "Val" "100n"
			(at 61.725 237.025 0)
			(layer "B.Fab")
			(hide yes)
			(effects
				(font
					(size 1 1)
					(thickness 0.15)
				)
				(justify mirror)
			)
		)
		(property "Voltage" ""
			(at 61.725 237.025 0)
			(layer "B.Fab")
			(hide yes)
			(effects
				(font
					(size 1 1)
					(thickness 0.15)
				)
				(justify mirror)
			)
		)
		(sheetname "LPDDR4")
		(sheetfile "lpddr4.kicad_sch")
		(attr smd)
		(fp_rect
			(start -0.72 0.38)
			(end 0.72 -0.38)
			(stroke
				(width 0.05)
				(type solid)
			)
			(fill no)
			(layer "B.CrtYd")
		)
		(fp_rect
			(start 0.3 -0.15)
			(end -0.301 0.149)
			(stroke
				(width 0.15)
				(type solid)
			)
			(fill no)
			(layer "B.Fab")
		)
		(pad "" smd roundrect
			(at -0.349 0.002 270)
			(size 0.318 0.36)
			(layers "B.Paste")
			(roundrect_rratio 0.25)
		)
		(pad "" smd roundrect
			(at 0.341 0.002 270)
			(size 0.318 0.36)
			(layers "B.Paste")
			(roundrect_rratio 0.25)
		)
		(pad "1" smd roundrect
			(at -0.321 0.002 270)
			(size 0.46 0.4)
			(layers "B.Cu" "B.Mask")
			(roundrect_rratio 0.25)
			(net 36 "GND")
			(pintype "passive")
		)
		(pad "2" smd roundrect
			(at 0.32 0.002 270)
			(size 0.46 0.4)
			(layers "B.Cu" "B.Mask")
			(roundrect_rratio 0.25)
			(net 188 "VDD2")
			(pintype "passive")
		)
	)
	(footprint "antmicro-footprints:C_0201"
		(layer "B.Cu")
		(at 149.375 89.15 -90)
		(descr "Capacitor SMD 0201")
		(tags "capacitor SMD 0201")
		(property "Reference" "C28"
			(at -0.9 -1.2 90)
			(layer "B.SilkS")
			(effects
				(font
					(size 0.7 0.7)
					(thickness 0.15)
				)
				(justify left bottom mirror)
			)
		)
		(property "Value" "C_100n_0201"
			(at 0 -1.4 90)
			(layer "B.Fab")
			(effects
				(font
					(size 0.7 0.7)
					(thickness 0.15)
				)
				(justify left bottom mirror)
			)
		)
		(property "Description" " "
			(at 0 0 270)
			(layer "F.Fab")
			(hide yes)
			(effects
				(font
					(size 1.27 1.27)
					(thickness 0.15)
				)
			)
		)
		(property "Author" "Antmicro"
			(at 60.225 238.525 0)
			(layer "B.Fab")
			(hide yes)
			(effects
				(font
					(size 1 1)
					(thickness 0.15)
				)
				(justify mirror)
			)
		)
		(property "Dielectric" ""
			(at 60.225 238.525 0)
			(layer "B.Fab")
			(hide yes)
			(effects
				(font
					(size 1 1)
					(thickness 0.15)
				)
				(justify mirror)
			)
		)
		(property "License" "Apache-2.0"
			(at 60.225 238.525 0)
			(layer "B.Fab")
			(hide yes)
			(effects
				(font
					(size 1 1)
					(thickness 0.15)
				)
				(justify mirror)
			)
		)
		(property "MPN" "CC0201KRX6S5BB104"
			(at 60.225 238.525 0)
			(layer "B.Fab")
			(hide yes)
			(effects
				(font
					(size 1 1)
					(thickness 0.15)
				)
				(justify mirror)
			)
		)
		(property "Manufacturer" "YAGEO"
			(at 60.225 238.525 0)
			(layer "B.Fab")
			(hide yes)
			(effects
				(font
					(size 1 1)
					(thickness 0.15)
				)
				(justify mirror)
			)
		)
		(property "Val" "100n"
			(at 60.225 238.525 0)
			(layer "B.Fab")
			(hide yes)
			(effects
				(font
					(size 1 1)
					(thickness 0.15)
				)
				(justify mirror)
			)
		)
		(property "Voltage" ""
			(at 60.225 238.525 0)
			(layer "B.Fab")
			(hide yes)
			(effects
				(font
					(size 1 1)
					(thickness 0.15)
				)
				(justify mirror)
			)
		)
		(sheetname "LPDDR4")
		(sheetfile "lpddr4.kicad_sch")
		(attr smd)
		(fp_rect
			(start -0.72 0.38)
			(end 0.72 -0.38)
			(stroke
				(width 0.05)
				(type solid)
			)
			(fill no)
			(layer "B.CrtYd")
		)
		(fp_rect
			(start 0.3 -0.15)
			(end -0.301 0.149)
			(stroke
				(width 0.15)
				(type solid)
			)
			(fill no)
			(layer "B.Fab")
		)
		(pad "" smd roundrect
			(at -0.349 0.002 270)
			(size 0.318 0.36)
			(layers "B.Paste")
			(roundrect_rratio 0.25)
		)
		(pad "" smd roundrect
			(at 0.341 0.002 270)
			(size 0.318 0.36)
			(layers "B.Paste")
			(roundrect_rratio 0.25)
		)
		(pad "1" smd roundrect
			(at -0.321 0.002 270)
			(size 0.46 0.4)
			(layers "B.Cu" "B.Mask")
			(roundrect_rratio 0.25)
			(net 36 "GND")
			(pintype "passive")
		)
		(pad "2" smd roundrect
			(at 0.32 0.002 270)
			(size 0.46 0.4)
			(layers "B.Cu" "B.Mask")
			(roundrect_rratio 0.25)
			(net 188 "VDD2")
			(pintype "passive")
		)
	)
	(footprint "antmicro-footprints:C_0201"
		(layer "B.Cu")
		(at 148.075 86.1 180)
		(descr "Capacitor SMD 0201")
		(tags "capacitor SMD 0201")
		(property "Reference" "C29"
			(at -0.9 0.45 0)
			(layer "B.SilkS")
			(effects
				(font
					(size 0.7 0.7)
					(thickness 0.15)
				)
				(justify left bottom mirror)
			)
		)
		(property "Value" "C_100n_0201"
			(at 0 -1.4 0)
			(layer "B.Fab")
			(effects
				(font
					(size 0.7 0.7)
					(thickness 0.15)
				)
				(justify left bottom mirror)
			)
		)
		(property "Description" " "
			(at 0 0 180)
			(layer "F.Fab")
			(hide yes)
			(effects
				(font
					(size 1.27 1.27)
					(thickness 0.15)
				)
			)
		)
		(property "Author" "Antmicro"
			(at 296.15 172.2 0)
			(layer "B.Fab")
			(hide yes)
			(effects
				(font
					(size 1 1)
					(thickness 0.15)
				)
				(justify mirror)
			)
		)
		(property "Dielectric" ""
			(at 296.15 172.2 0)
			(layer "B.Fab")
			(hide yes)
			(effects
				(font
					(size 1 1)
					(thickness 0.15)
				)
				(justify mirror)
			)
		)
		(property "License" "Apache-2.0"
			(at 296.15 172.2 0)
			(layer "B.Fab")
			(hide yes)
			(effects
				(font
					(size 1 1)
					(thickness 0.15)
				)
				(justify mirror)
			)
		)
		(property "MPN" "CC0201KRX6S5BB104"
			(at 296.15 172.2 0)
			(layer "B.Fab")
			(hide yes)
			(effects
				(font
					(size 1 1)
					(thickness 0.15)
				)
				(justify mirror)
			)
		)
		(property "Manufacturer" "YAGEO"
			(at 296.15 172.2 0)
			(layer "B.Fab")
			(hide yes)
			(effects
				(font
					(size 1 1)
					(thickness 0.15)
				)
				(justify mirror)
			)
		)
		(property "Val" "100n"
			(at 296.15 172.2 0)
			(layer "B.Fab")
			(hide yes)
			(effects
				(font
					(size 1 1)
					(thickness 0.15)
				)
				(justify mirror)
			)
		)
		(property "Voltage" ""
			(at 296.15 172.2 0)
			(layer "B.Fab")
			(hide yes)
			(effects
				(font
					(size 1 1)
					(thickness 0.15)
				)
				(justify mirror)
			)
		)
		(sheetname "LPDDR4")
		(sheetfile "lpddr4.kicad_sch")
		(attr smd)
		(fp_rect
			(start -0.72 0.38)
			(end 0.72 -0.38)
			(stroke
				(width 0.05)
				(type solid)
			)
			(fill no)
			(layer "B.CrtYd")
		)
		(fp_rect
			(start 0.3 -0.15)
			(end -0.301 0.149)
			(stroke
				(width 0.15)
				(type solid)
			)
			(fill no)
			(layer "B.Fab")
		)
		(pad "" smd roundrect
			(at -0.349 0.002 180)
			(size 0.318 0.36)
			(layers "B.Paste")
			(roundrect_rratio 0.25)
		)
		(pad "" smd roundrect
			(at 0.341 0.002 180)
			(size 0.318 0.36)
			(layers "B.Paste")
			(roundrect_rratio 0.25)
		)
		(pad "1" smd roundrect
			(at -0.321 0.002 180)
			(size 0.46 0.4)
			(layers "B.Cu" "B.Mask")
			(roundrect_rratio 0.25)
			(net 36 "GND")
			(pintype "passive")
		)
		(pad "2" smd roundrect
			(at 0.32 0.002 180)
			(size 0.46 0.4)
			(layers "B.Cu" "B.Mask")
			(roundrect_rratio 0.25)
			(net 187 "VDD1")
			(pintype "passive")
		)
	)
	(footprint "antmicro-footprints:C_0201"
		(layer "B.Cu")
		(at 153.075 86.15)
		(descr "Capacitor SMD 0201")
		(tags "capacitor SMD 0201")
		(property "Reference" "C30"
			(at -0.8 1.2 0)
			(layer "B.SilkS")
			(effects
				(font
					(size 0.7 0.7)
					(thickness 0.15)
				)
				(justify right bottom mirror)
			)
		)
		(property "Value" "C_100n_0201"
			(at 0 -1.4 0)
			(layer "B.Fab")
			(effects
				(font
					(size 0.7 0.7)
					(thickness 0.15)
				)
				(justify right bottom mirror)
			)
		)
		(property "Description" " "
			(at 0 0 0)
			(layer "F.Fab")
			(hide yes)
			(effects
				(font
					(size 1.27 1.27)
					(thickness 0.15)
				)
			)
		)
		(property "Author" "Antmicro"
			(at 0 0 0)
			(layer "B.Fab")
			(hide yes)
			(effects
				(font
					(size 1 1)
					(thickness 0.15)
				)
				(justify mirror)
			)
		)
		(property "Dielectric" ""
			(at 0 0 0)
			(layer "B.Fab")
			(hide yes)
			(effects
				(font
					(size 1 1)
					(thickness 0.15)
				)
				(justify mirror)
			)
		)
		(property "License" "Apache-2.0"
			(at 0 0 0)
			(layer "B.Fab")
			(hide yes)
			(effects
				(font
					(size 1 1)
					(thickness 0.15)
				)
				(justify mirror)
			)
		)
		(property "MPN" "CC0201KRX6S5BB104"
			(at 0 0 0)
			(layer "B.Fab")
			(hide yes)
			(effects
				(font
					(size 1 1)
					(thickness 0.15)
				)
				(justify mirror)
			)
		)
		(property "Manufacturer" "YAGEO"
			(at 0 0 0)
			(layer "B.Fab")
			(hide yes)
			(effects
				(font
					(size 1 1)
					(thickness 0.15)
				)
				(justify mirror)
			)
		)
		(property "Val" "100n"
			(at 0 0 0)
			(layer "B.Fab")
			(hide yes)
			(effects
				(font
					(size 1 1)
					(thickness 0.15)
				)
				(justify mirror)
			)
		)
		(property "Voltage" ""
			(at 0 0 0)
			(layer "B.Fab")
			(hide yes)
			(effects
				(font
					(size 1 1)
					(thickness 0.15)
				)
				(justify mirror)
			)
		)
		(sheetname "LPDDR4")
		(sheetfile "lpddr4.kicad_sch")
		(attr smd)
		(fp_rect
			(start -0.72 0.38)
			(end 0.72 -0.38)
			(stroke
				(width 0.05)
				(type solid)
			)
			(fill no)
			(layer "B.CrtYd")
		)
		(fp_rect
			(start 0.3 -0.15)
			(end -0.301 0.149)
			(stroke
				(width 0.15)
				(type solid)
			)
			(fill no)
			(layer "B.Fab")
		)
		(pad "" smd roundrect
			(at -0.349 0.002)
			(size 0.318 0.36)
			(layers "B.Paste")
			(roundrect_rratio 0.25)
		)
		(pad "" smd roundrect
			(at 0.341 0.002)
			(size 0.318 0.36)
			(layers "B.Paste")
			(roundrect_rratio 0.25)
		)
		(pad "1" smd roundrect
			(at -0.321 0.002)
			(size 0.46 0.4)
			(layers "B.Cu" "B.Mask")
			(roundrect_rratio 0.25)
			(net 36 "GND")
			(pintype "passive")
		)
		(pad "2" smd roundrect
			(at 0.32 0.002)
			(size 0.46 0.4)
			(layers "B.Cu" "B.Mask")
			(roundrect_rratio 0.25)
			(net 188 "VDD2")
			(pintype "passive")
		)
	)
	(footprint "antmicro-footprints:C_0201"
		(layer "B.Cu")
		(at 149.375 82.95 -90)
		(descr "Capacitor SMD 0201")
		(tags "capacitor SMD 0201")
		(property "Reference" "C32"
			(at -1.1 0.4 90)
			(layer "B.SilkS")
			(effects
				(font
					(size 0.7 0.7)
					(thickness 0.15)
				)
				(justify left bottom mirror)
			)
		)
		(property "Value" "C_100n_0201"
			(at 0 -1.4 90)
			(layer "B.Fab")
			(effects
				(font
					(size 0.7 0.7)
					(thickness 0.15)
				)
				(justify left bottom mirror)
			)
		)
		(property "Description" " "
			(at 0 0 270)
			(layer "F.Fab")
			(hide yes)
			(effects
				(font
					(size 1.27 1.27)
					(thickness 0.15)
				)
			)
		)
		(property "Author" "Antmicro"
			(at 66.425 232.325 0)
			(layer "B.Fab")
			(hide yes)
			(effects
				(font
					(size 1 1)
					(thickness 0.15)
				)
				(justify mirror)
			)
		)
		(property "Dielectric" ""
			(at 66.425 232.325 0)
			(layer "B.Fab")
			(hide yes)
			(effects
				(font
					(size 1 1)
					(thickness 0.15)
				)
				(justify mirror)
			)
		)
		(property "License" "Apache-2.0"
			(at 66.425 232.325 0)
			(layer "B.Fab")
			(hide yes)
			(effects
				(font
					(size 1 1)
					(thickness 0.15)
				)
				(justify mirror)
			)
		)
		(property "MPN" "CC0201KRX6S5BB104"
			(at 66.425 232.325 0)
			(layer "B.Fab")
			(hide yes)
			(effects
				(font
					(size 1 1)
					(thickness 0.15)
				)
				(justify mirror)
			)
		)
		(property "Manufacturer" "YAGEO"
			(at 66.425 232.325 0)
			(layer "B.Fab")
			(hide yes)
			(effects
				(font
					(size 1 1)
					(thickness 0.15)
				)
				(justify mirror)
			)
		)
		(property "Val" "100n"
			(at 66.425 232.325 0)
			(layer "B.Fab")
			(hide yes)
			(effects
				(font
					(size 1 1)
					(thickness 0.15)
				)
				(justify mirror)
			)
		)
		(property "Voltage" ""
			(at 66.425 232.325 0)
			(layer "B.Fab")
			(hide yes)
			(effects
				(font
					(size 1 1)
					(thickness 0.15)
				)
				(justify mirror)
			)
		)
		(sheetname "LPDDR4")
		(sheetfile "lpddr4.kicad_sch")
		(attr smd)
		(fp_rect
			(start -0.72 0.38)
			(end 0.72 -0.38)
			(stroke
				(width 0.05)
				(type solid)
			)
			(fill no)
			(layer "B.CrtYd")
		)
		(fp_rect
			(start 0.3 -0.15)
			(end -0.301 0.149)
			(stroke
				(width 0.15)
				(type solid)
			)
			(fill no)
			(layer "B.Fab")
		)
		(pad "" smd roundrect
			(at -0.349 0.002 270)
			(size 0.318 0.36)
			(layers "B.Paste")
			(roundrect_rratio 0.25)
		)
		(pad "" smd roundrect
			(at 0.341 0.002 270)
			(size 0.318 0.36)
			(layers "B.Paste")
			(roundrect_rratio 0.25)
		)
		(pad "1" smd roundrect
			(at -0.321 0.002 270)
			(size 0.46 0.4)
			(layers "B.Cu" "B.Mask")
			(roundrect_rratio 0.25)
			(net 36 "GND")
			(pintype "passive")
		)
		(pad "2" smd roundrect
			(at 0.32 0.002 270)
			(size 0.46 0.4)
			(layers "B.Cu" "B.Mask")
			(roundrect_rratio 0.25)
			(net 188 "VDD2")
			(pintype "passive")
		)
	)
	(footprint "antmicro-footprints:C_0201"
		(layer "B.Cu")
		(at 149.375 84.45 -90)
		(descr "Capacitor SMD 0201")
		(tags "capacitor SMD 0201")
		(property "Reference" "C33"
			(at -0.9 -1.2 90)
			(layer "B.SilkS")
			(effects
				(font
					(size 0.7 0.7)
					(thickness 0.15)
				)
				(justify left bottom mirror)
			)
		)
		(property "Value" "C_100n_0201"
			(at 0 -1.4 90)
			(layer "B.Fab")
			(effects
				(font
					(size 0.7 0.7)
					(thickness 0.15)
				)
				(justify left bottom mirror)
			)
		)
		(property "Description" " "
			(at 0 0 270)
			(layer "F.Fab")
			(hide yes)
			(effects
				(font
					(size 1.27 1.27)
					(thickness 0.15)
				)
			)
		)
		(property "Author" "Antmicro"
			(at 64.925 233.825 0)
			(layer "B.Fab")
			(hide yes)
			(effects
				(font
					(size 1 1)
					(thickness 0.15)
				)
				(justify mirror)
			)
		)
		(property "Dielectric" ""
			(at 64.925 233.825 0)
			(layer "B.Fab")
			(hide yes)
			(effects
				(font
					(size 1 1)
					(thickness 0.15)
				)
				(justify mirror)
			)
		)
		(property "License" "Apache-2.0"
			(at 64.925 233.825 0)
			(layer "B.Fab")
			(hide yes)
			(effects
				(font
					(size 1 1)
					(thickness 0.15)
				)
				(justify mirror)
			)
		)
		(property "MPN" "CC0201KRX6S5BB104"
			(at 64.925 233.825 0)
			(layer "B.Fab")
			(hide yes)
			(effects
				(font
					(size 1 1)
					(thickness 0.15)
				)
				(justify mirror)
			)
		)
		(property "Manufacturer" "YAGEO"
			(at 64.925 233.825 0)
			(layer "B.Fab")
			(hide yes)
			(effects
				(font
					(size 1 1)
					(thickness 0.15)
				)
				(justify mirror)
			)
		)
		(property "Val" "100n"
			(at 64.925 233.825 0)
			(layer "B.Fab")
			(hide yes)
			(effects
				(font
					(size 1 1)
					(thickness 0.15)
				)
				(justify mirror)
			)
		)
		(property "Voltage" ""
			(at 64.925 233.825 0)
			(layer "B.Fab")
			(hide yes)
			(effects
				(font
					(size 1 1)
					(thickness 0.15)
				)
				(justify mirror)
			)
		)
		(sheetname "LPDDR4")
		(sheetfile "lpddr4.kicad_sch")
		(attr smd)
		(fp_rect
			(start -0.72 0.38)
			(end 0.72 -0.38)
			(stroke
				(width 0.05)
				(type solid)
			)
			(fill no)
			(layer "B.CrtYd")
		)
		(fp_rect
			(start 0.3 -0.15)
			(end -0.301 0.149)
			(stroke
				(width 0.15)
				(type solid)
			)
			(fill no)
			(layer "B.Fab")
		)
		(pad "" smd roundrect
			(at -0.349 0.002 270)
			(size 0.318 0.36)
			(layers "B.Paste")
			(roundrect_rratio 0.25)
		)
		(pad "" smd roundrect
			(at 0.341 0.002 270)
			(size 0.318 0.36)
			(layers "B.Paste")
			(roundrect_rratio 0.25)
		)
		(pad "1" smd roundrect
			(at -0.321 0.002 270)
			(size 0.46 0.4)
			(layers "B.Cu" "B.Mask")
			(roundrect_rratio 0.25)
			(net 36 "GND")
			(pintype "passive")
		)
		(pad "2" smd roundrect
			(at 0.32 0.002 270)
			(size 0.46 0.4)
			(layers "B.Cu" "B.Mask")
			(roundrect_rratio 0.25)
			(net 188 "VDD2")
			(pintype "passive")
		)
	)
	(footprint "antmicro-footprints:C_0201"
		(layer "B.Cu")
		(at 144.975 86.1 180)
		(descr "Capacitor SMD 0201")
		(tags "capacitor SMD 0201")
		(property "Reference" "C35"
			(at -0.9 0.45 0)
			(layer "B.SilkS")
			(effects
				(font
					(size 0.7 0.7)
					(thickness 0.15)
				)
				(justify left bottom mirror)
			)
		)
		(property "Value" "C_100n_0201"
			(at 0 -1.4 0)
			(layer "B.Fab")
			(effects
				(font
					(size 0.7 0.7)
					(thickness 0.15)
				)
				(justify left bottom mirror)
			)
		)
		(property "Description" " "
			(at 0 0 180)
			(layer "F.Fab")
			(hide yes)
			(effects
				(font
					(size 1.27 1.27)
					(thickness 0.15)
				)
			)
		)
		(property "Author" "Antmicro"
			(at 289.95 172.2 0)
			(layer "B.Fab")
			(hide yes)
			(effects
				(font
					(size 1 1)
					(thickness 0.15)
				)
				(justify mirror)
			)
		)
		(property "Dielectric" ""
			(at 289.95 172.2 0)
			(layer "B.Fab")
			(hide yes)
			(effects
				(font
					(size 1 1)
					(thickness 0.15)
				)
				(justify mirror)
			)
		)
		(property "License" "Apache-2.0"
			(at 289.95 172.2 0)
			(layer "B.Fab")
			(hide yes)
			(effects
				(font
					(size 1 1)
					(thickness 0.15)
				)
				(justify mirror)
			)
		)
		(property "MPN" "CC0201KRX6S5BB104"
			(at 289.95 172.2 0)
			(layer "B.Fab")
			(hide yes)
			(effects
				(font
					(size 1 1)
					(thickness 0.15)
				)
				(justify mirror)
			)
		)
		(property "Manufacturer" "YAGEO"
			(at 289.95 172.2 0)
			(layer "B.Fab")
			(hide yes)
			(effects
				(font
					(size 1 1)
					(thickness 0.15)
				)
				(justify mirror)
			)
		)
		(property "Val" "100n"
			(at 289.95 172.2 0)
			(layer "B.Fab")
			(hide yes)
			(effects
				(font
					(size 1 1)
					(thickness 0.15)
				)
				(justify mirror)
			)
		)
		(property "Voltage" ""
			(at 289.95 172.2 0)
			(layer "B.Fab")
			(hide yes)
			(effects
				(font
					(size 1 1)
					(thickness 0.15)
				)
				(justify mirror)
			)
		)
		(sheetname "LPDDR4")
		(sheetfile "lpddr4.kicad_sch")
		(attr smd)
		(fp_rect
			(start -0.72 0.38)
			(end 0.72 -0.38)
			(stroke
				(width 0.05)
				(type solid)
			)
			(fill no)
			(layer "B.CrtYd")
		)
		(fp_rect
			(start 0.3 -0.15)
			(end -0.301 0.149)
			(stroke
				(width 0.15)
				(type solid)
			)
			(fill no)
			(layer "B.Fab")
		)
		(pad "" smd roundrect
			(at -0.349 0.002 180)
			(size 0.318 0.36)
			(layers "B.Paste")
			(roundrect_rratio 0.25)
		)
		(pad "" smd roundrect
			(at 0.341 0.002 180)
			(size 0.318 0.36)
			(layers "B.Paste")
			(roundrect_rratio 0.25)
		)
		(pad "1" smd roundrect
			(at -0.321 0.002 180)
			(size 0.46 0.4)
			(layers "B.Cu" "B.Mask")
			(roundrect_rratio 0.25)
			(net 36 "GND")
			(pintype "passive")
		)
		(pad "2" smd roundrect
			(at 0.32 0.002 180)
			(size 0.46 0.4)
			(layers "B.Cu" "B.Mask")
			(roundrect_rratio 0.25)
			(net 188 "VDD2")
			(pintype "passive")
		)
	)
	(footprint "antmicro-footprints:C_0201"
		(layer "B.Cu")
		(at 146.575 86.1 180)
		(descr "Capacitor SMD 0201")
		(tags "capacitor SMD 0201")
		(property "Reference" "C36"
			(at -1.1 -1.25 0)
			(layer "B.SilkS")
			(effects
				(font
					(size 0.7 0.7)
					(thickness 0.15)
				)
				(justify left bottom mirror)
			)
		)
		(property "Value" "C_100n_0201"
			(at 0 -1.4 0)
			(layer "B.Fab")
			(effects
				(font
					(size 0.7 0.7)
					(thickness 0.15)
				)
				(justify left bottom mirror)
			)
		)
		(property "Description" " "
			(at 0 0 180)
			(layer "F.Fab")
			(hide yes)
			(effects
				(font
					(size 1.27 1.27)
					(thickness 0.15)
				)
			)
		)
		(property "Author" "Antmicro"
			(at 293.15 172.2 0)
			(layer "B.Fab")
			(hide yes)
			(effects
				(font
					(size 1 1)
					(thickness 0.15)
				)
				(justify mirror)
			)
		)
		(property "Dielectric" ""
			(at 293.15 172.2 0)
			(layer "B.Fab")
			(hide yes)
			(effects
				(font
					(size 1 1)
					(thickness 0.15)
				)
				(justify mirror)
			)
		)
		(property "License" "Apache-2.0"
			(at 293.15 172.2 0)
			(layer "B.Fab")
			(hide yes)
			(effects
				(font
					(size 1 1)
					(thickness 0.15)
				)
				(justify mirror)
			)
		)
		(property "MPN" "CC0201KRX6S5BB104"
			(at 293.15 172.2 0)
			(layer "B.Fab")
			(hide yes)
			(effects
				(font
					(size 1 1)
					(thickness 0.15)
				)
				(justify mirror)
			)
		)
		(property "Manufacturer" "YAGEO"
			(at 293.15 172.2 0)
			(layer "B.Fab")
			(hide yes)
			(effects
				(font
					(size 1 1)
					(thickness 0.15)
				)
				(justify mirror)
			)
		)
		(property "Val" "100n"
			(at 293.15 172.2 0)
			(layer "B.Fab")
			(hide yes)
			(effects
				(font
					(size 1 1)
					(thickness 0.15)
				)
				(justify mirror)
			)
		)
		(property "Voltage" ""
			(at 293.15 172.2 0)
			(layer "B.Fab")
			(hide yes)
			(effects
				(font
					(size 1 1)
					(thickness 0.15)
				)
				(justify mirror)
			)
		)
		(sheetname "LPDDR4")
		(sheetfile "lpddr4.kicad_sch")
		(attr smd)
		(fp_rect
			(start -0.72 0.38)
			(end 0.72 -0.38)
			(stroke
				(width 0.05)
				(type solid)
			)
			(fill no)
			(layer "B.CrtYd")
		)
		(fp_rect
			(start 0.3 -0.15)
			(end -0.301 0.149)
			(stroke
				(width 0.15)
				(type solid)
			)
			(fill no)
			(layer "B.Fab")
		)
		(pad "" smd roundrect
			(at -0.349 0.002 180)
			(size 0.318 0.36)
			(layers "B.Paste")
			(roundrect_rratio 0.25)
		)
		(pad "" smd roundrect
			(at 0.341 0.002 180)
			(size 0.318 0.36)
			(layers "B.Paste")
			(roundrect_rratio 0.25)
		)
		(pad "1" smd roundrect
			(at -0.321 0.002 180)
			(size 0.46 0.4)
			(layers "B.Cu" "B.Mask")
			(roundrect_rratio 0.25)
			(net 36 "GND")
			(pintype "passive")
		)
		(pad "2" smd roundrect
			(at 0.32 0.002 180)
			(size 0.46 0.4)
			(layers "B.Cu" "B.Mask")
			(roundrect_rratio 0.25)
			(net 188 "VDD2")
			(pintype "passive")
		)
	)
	(gr_arc
		(start 101.75 81.35)
		(mid 101.559619 81.809619)
		(end 101.1 82)
		(stroke
			(width 0.15)
			(type solid)
		)
		(layer "Edge.Cuts")
	)
	(gr_arc
		(start 168.5 82)
		(mid 168.040381 81.809619)
		(end 167.85 81.35)
		(stroke
			(width 0.15)
			(type solid)
		)
		(layer "Edge.Cuts")
	)
	(gr_line
		(start 169.6 78)
		(end 168.5 78)
		(stroke
			(width 0.15)
			(type solid)
		)
		(layer "Edge.Cuts")
	)
	(gr_line
		(start 167.85 81.35)
		(end 167.85 78.65)
		(stroke
			(width 0.15)
			(type solid)
		)
		(layer "Edge.Cuts")
	)
	(gr_line
		(start 168.5 82)
		(end 169.6 82)
		(stroke
			(width 0.15)
			(type solid)
		)
		(layer "Edge.Cuts")
	)
	(gr_line
		(start 141.3 70)
		(end 168.851561 70)
		(stroke
			(width 0.15)
			(type solid)
		)
		(layer "Edge.Cuts")
	)
	(gr_line
		(start 100.75 70)
		(end 135.3 70)
		(stroke
			(width 0.15)
			(type solid)
		)
		(layer "Edge.Cuts")
	)
	(gr_arc
		(start 167.85 78.65)
		(mid 168.040381 78.190381)
		(end 168.5 78)
		(stroke
			(width 0.15)
			(type solid)
		)
		(layer "Edge.Cuts")
	)
	(gr_line
		(start 101.75 81.35)
		(end 101.75 78.65)
		(stroke
			(width 0.15)
			(type solid)
		)
		(layer "Edge.Cuts")
	)
	(gr_line
		(start 101.1 78)
		(end 100 78)
		(stroke
			(width 0.15)
			(type solid)
		)
		(layer "Edge.Cuts")
	)
	(gr_line
		(start 100 78)
		(end 100 70.75)
		(stroke
			(width 0.15)
			(type solid)
		)
		(layer "Edge.Cuts")
	)
	(gr_arc
		(start 168.851561 70)
		(mid 169.380883 70.220221)
		(end 169.600002 70.75)
		(stroke
			(width 0.15)
			(type solid)
		)
		(layer "Edge.Cuts")
	)
	(gr_line
		(start 100 96)
		(end 100 82)
		(stroke
			(width 0.15)
			(type solid)
		)
		(layer "Edge.Cuts")
	)
	(gr_line
		(start 169.6 96)
		(end 169.6 82)
		(stroke
			(width 0.15)
			(type solid)
		)
		(layer "Edge.Cuts")
	)
	(gr_arc
		(start 141.3 75)
		(mid 138.3 78)
		(end 135.3 75)
		(stroke
			(width 0.15)
			(type solid)
		)
		(layer "Edge.Cuts")
	)
	(gr_line
		(start 141.3 75)
		(end 141.3 70)
		(stroke
			(width 0.15)
			(type solid)
		)
		(layer "Edge.Cuts")
	)
	(gr_arc
		(start 100 70.75)
		(mid 100.21967 70.21967)
		(end 100.75 70)
		(stroke
			(width 0.15)
			(type solid)
		)
		(layer "Edge.Cuts")
	)
	(gr_arc
		(start 101.1 78)
		(mid 101.559619 78.190381)
		(end 101.75 78.65)
		(stroke
			(width 0.15)
			(type solid)
		)
		(layer "Edge.Cuts")
	)
	(gr_line
		(start 100 82)
		(end 101.1 82)
		(stroke
			(width 0.15)
			(type solid)
		)
		(layer "Edge.Cuts")
	)
	(gr_line
		(start 135.3 75)
		(end 135.3 70)
		(stroke
			(width 0.15)
			(type solid)
		)
		(layer "Edge.Cuts")
	)
	(gr_line
		(start 169.6 78)
		(end 169.600002 70.75)
		(stroke
			(width 0.15)
			(type solid)
		)
		(layer "Edge.Cuts")
	)
	(gr_text "LPDDR4 Testbed\nRev. ${REVISION}  03/2024"
		(at 108.525 78.2 0)
		(layer "F.Cu")
		(effects
			(font
				(size 0.85 0.85)
				(thickness 0.18)
			)
			(justify left)
		)
	)
	(segment
		(start 124.105 83.58)
		(end 124.105 81.375)
		(width 0.2)
		(layer "F.Cu")
		(net 1)
	)
	(segment
		(start 123.11 84.575)
		(end 124.105 83.58)
		(width 0.2)
		(layer "F.Cu")
		(net 1)
	)
	(segment
		(start 122.27501 84.575)
		(end 123.11 84.575)
		(width 0.2)
		(layer "F.Cu")
		(net 1)
	)
	(segment
		(start 124.105 81.375)
		(end 127.625 77.855)
		(width 0.2)
		(layer "F.Cu")
		(net 1)
	)
	(segment
		(start 127.625 77.855)
		(end 127.625 76.435)
		(width 0.2)
		(layer "F.Cu")
		(net 1)
	)
	(segment
		(start 123.12 85.225)
		(end 122.27501 85.225)
		(width 0.2)
		(layer "F.Cu")
		(net 2)
	)
	(segment
		(start 129.441666 76.958334)
		(end 124.67 81.73)
		(width 0.2)
		(layer "F.Cu")
		(net 2)
	)
	(segment
		(start 124.67 83.675)
		(end 123.12 85.225)
		(width 0.2)
		(layer "F.Cu")
		(net 2)
	)
	(segment
		(start 124.67 81.73)
		(end 124.67 83.675)
		(width 0.2)
		(layer "F.Cu")
		(net 2)
	)
	(segment
		(start 129.441666 76.435)
		(end 129.441666 76.958334)
		(width 0.2)
		(layer "F.Cu")
		(net 2)
	)
	(segment
		(start 123.11 85.875)
		(end 122.27501 85.875)
		(width 0.2)
		(layer "F.Cu")
		(net 3)
	)
	(segment
		(start 131.258332 77.666668)
		(end 130.64 78.285)
		(width 0.2)
		(layer "F.Cu")
		(net 3)
	)
	(segment
		(start 125.31 83.675)
		(end 123.11 85.875)
		(width 0.2)
		(layer "F.Cu")
		(net 3)
	)
	(segment
		(start 130.64 78.285)
		(end 128.99 78.285)
		(width 0.2)
		(layer "F.Cu")
		(net 3)
	)
	(segment
		(start 131.258332 76.435)
		(end 131.258332 77.666668)
		(width 0.2)
		(layer "F.Cu")
		(net 3)
	)
	(segment
		(start 125.31 81.965)
		(end 125.31 83.675)
		(width 0.2)
		(layer "F.Cu")
		(net 3)
	)
	(segment
		(start 128.99 78.285)
		(end 125.31 81.965)
		(width 0.2)
		(layer "F.Cu")
		(net 3)
	)
	(segment
		(start 151.925 98.7)
		(end 151.925 96.825)
		(width 0.2)
		(layer "F.Cu")
		(net 36)
	)
	(segment
		(start 147.275 87.1)
		(end 146.975 86.8)
		(width 0.1)
		(layer "F.Cu")
		(net 36)
	)
	(segment
		(start 147.375 87.1)
		(end 147.275 87.1)
		(width 0.1)
		(layer "F.Cu")
		(net 36)
	)
	(segment
		(start 152.84333 85.15)
		(end 152.58628 85.40705)
		(width 0.1)
		(layer "F.Cu")
		(net 36)
	)
	(segment
		(start 152.975 85.15)
		(end 152.84333 85.15)
		(width 0.1)
		(layer "F.Cu")
		(net 36)
	)
	(segment
		(start 152.875 87.1)
		(end 152.575 86.8)
		(width 0.1)
		(layer "F.Cu")
		(net 36)
	)
	(segment
		(start 152.975 87.1)
		(end 152.875 87.1)
		(width 0.1)
		(layer "F.Cu")
		(net 36)
	)
	(segment
		(start 144.875 87.75)
		(end 144.575 87.45)
		(width 0.1)
		(layer "F.Cu")
		(net 36)
	)
	(segment
		(start 144.975 87.75)
		(end 144.875 87.75)
		(width 0.1)
		(layer "F.Cu")
		(net 36)
	)
	(segment
		(start 146.575 87.75)
		(end 146.475 87.75)
		(width 0.1)
		(layer "F.Cu")
		(net 36)
	)
	(segment
		(start 146.475 87.75)
		(end 146.175 87.45)
		(width 0.1)
		(layer "F.Cu")
		(net 36)
	)
	(segment
		(start 153.875 87.75)
		(end 154.175 88.05)
		(width 0.1)
		(layer "F.Cu")
		(net 36)
	)
	(segment
		(start 153.775 87.75)
		(end 153.875 87.75)
		(width 0.1)
		(layer "F.Cu")
		(net 36)
	)
	(segment
		(start 144.875 80.6)
		(end 144.575 80.3)
		(width 0.1)
		(layer "F.Cu")
		(net 36)
	)
	(segment
		(start 144.975 80.6)
		(end 144.875 80.6)
		(width 0.1)
		(layer "F.Cu")
		(net 36)
	)
	(segment
		(start 148.275 83.2)
		(end 148.575 83.5)
		(width 0.1)
		(layer "F.Cu")
		(net 36)
	)
	(segment
		(start 148.175 83.2)
		(end 148.275 83.2)
		(width 0.1)
		(layer "F.Cu")
		(net 36)
	)
	(segment
		(start 152.975 81.25)
		(end 153.075 81.25)
		(width 0.1)
		(layer "F.Cu")
		(net 36)
	)
	(segment
		(start 153.075 81.25)
		(end 153.375 81.55)
		(width 0.1)
		(layer "F.Cu")
		(net 36)
	)
	(segment
		(start 150.575 79.3)
		(end 150.525 79.3)
		(width 0.1)
		(layer "F.Cu")
		(net 36)
	)
	(segment
		(start 150.525 79.3)
		(end 150.17502 79.64998)
		(width 0.1)
		(layer "F.Cu")
		(net 36)
	)
	(segment
		(start 146.575 79.3)
		(end 146.575 78.8)
		(width 0.1)
		(layer "F.Cu")
		(net 36)
	)
	(segment
		(start 152.175 79.3)
		(end 152.175 78.8)
		(width 0.1)
		(layer "F.Cu")
		(net 36)
	)
	(segment
		(start 153.875 84.5)
		(end 154.175 84.8)
		(width 0.1)
		(layer "F.Cu")
		(net 36)
	)
	(segment
		(start 153.775 84.5)
		(end 153.875 84.5)
		(width 0.1)
		(layer "F.Cu")
		(net 36)
	)
	(segment
		(start 151.475 81.25)
		(end 151.775 81.55)
		(width 0.1)
		(layer "F.Cu")
		(net 36)
	)
	(segment
		(start 151.375 81.25)
		(end 151.475 81.25)
		(width 0.1)
		(layer "F.Cu")
		(net 36)
	)
	(segment
		(start 150.475 89.05)
		(end 150.175 88.75)
		(width 0.1)
		(layer "F.Cu")
		(net 36)
	)
	(segment
		(start 150.575 89.05)
		(end 150.475 89.05)
		(width 0.1)
		(layer "F.Cu")
		(net 36)
	)
	(segment
		(start 148.225 89.05)
		(end 148.575 88.7)
		(width 0.1)
		(layer "F.Cu")
		(net 36)
	)
	(segment
		(start 148.175 89.05)
		(end 148.225 89.05)
		(width 0.1)
		(layer "F.Cu")
		(net 36)
	)
	(segment
		(start 151.375 91)
		(end 151.475 91)
		(width 0.1)
		(layer "F.Cu")
		(net 36)
	)
	(segment
		(start 151.475 91)
		(end 151.775 91.3)
		(width 0.1)
		(layer "F.Cu")
		(net 36)
	)
	(segment
		(start 112.925 98.65)
		(end 112.925 97.1)
		(width 0.2)
		(layer "F.Cu")
		(net 36)
	)
	(segment
		(start 113.425 98.65)
		(end 113.425 97.2)
		(width 0.2)
		(layer "F.Cu")
		(net 36)
	)
	(segment
		(start 113.675 96.95)
		(end 113.675 96.45)
		(width 0.2)
		(layer "F.Cu")
		(net 36)
	)
	(segment
		(start 113.425 97.2)
		(end 113.675 96.95)
		(width 0.2)
		(layer "F.Cu")
		(net 36)
	)
	(segment
		(start 112.925 97.1)
		(end 113.175 96.85)
		(width 0.2)
		(layer "F.Cu")
		(net 36)
	)
	(segment
		(start 144.975 83.2)
		(end 143.575 83.2)
		(width 0.1)
		(layer "F.Cu")
		(net 36)
	)
	(segment
		(start 111.925 98.65)
		(end 111.925 97.1)
		(width 0.2)
		(layer "F.Cu")
		(net 36)
	)
	(segment
		(start 111.925 97.1)
		(end 112.175 96.85)
		(width 0.2)
		(layer "F.Cu")
		(net 36)
	)
	(segment
		(start 143.705 87.28)
		(end 143.875 87.45)
		(width 0.1)
		(layer "F.Cu")
		(net 36)
	)
	(segment
		(start 145.775 87.1)
		(end 145.675 87.1)
		(width 0.1)
		(layer "F.Cu")
		(net 36)
	)
	(segment
		(start 145.775 81.25)
		(end 145.875 81.25)
		(width 0.1)
		(layer "F.Cu")
		(net 36)
	)
	(segment
		(start 142.925 81.57)
		(end 143.825 81.57)
		(width 0.1)
		(layer "F.Cu")
		(net 36)
	)
	(segment
		(start 109.925 97.1)
		(end 110.175 96.85)
		(width 0.2)
		(layer "F.Cu")
		(net 36)
	)
	(segment
		(start 101.425 97.25)
		(end 101.675 97)
		(width 0.2)
		(layer "F.Cu")
		(net 36)
	)
	(segment
		(start 145.64333 85.15)
		(end 145.38628 85.40705)
		(width 0.1)
		(layer "F.Cu")
		(net 36)
	)
	(segment
		(start 152.095 78.37)
		(end 152.095 77.45)
		(width 0.1)
		(layer "F.Cu")
		(net 36)
	)
	(segment
		(start 143.27499 96.325)
		(end 143.27499 96.74999)
		(width 0.2)
		(layer "F.Cu")
		(net 36)
	)
	(segment
		(start 109.675 96.95)
		(end 109.675 96.45)
		(width 0.2)
		(layer "F.Cu")
		(net 36)
	)
	(segment
		(start 152.125 89.05)
		(end 151.775 89.4)
		(width 0.1)
		(layer "F.Cu")
		(net 36)
	)
	(segment
		(start 106.975 97.15)
		(end 107.225 96.9)
		(width 0.2)
		(layer "F.Cu")
		(net 36)
	)
	(segment
		(start 132.875 83.55)
		(end 131.875 83.55)
		(width 0.2)
		(layer "F.Cu")
		(net 36)
	)
	(segment
		(start 101.425 98.7)
		(end 101.425 97.25)
		(width 0.2)
		(layer "F.Cu")
		(net 36)
	)
	(segment
		(start 144.975 91.65)
		(end 144.675 91.65)
		(width 0.1)
		(layer "F.Cu")
		(net 36)
	)
	(segment
		(start 106.475 98.7)
		(end 106.475 97.25)
		(width 0.2)
		(layer "F.Cu")
		(net 36)
	)
	(segment
		(start 144.225 89.05)
		(end 144.975 89.05)
		(width 0.1)
		(layer "F.Cu")
		(net 36)
	)
	(segment
		(start 112.425 98.65)
		(end 112.425 97.2)
		(width 0.2)
		(layer "F.Cu")
		(net 36)
	)
	(segment
		(start 146.575 78.8)
		(end 146.575 77.48)
		(width 0.1)
		(layer "F.Cu")
		(net 36)
	)
	(segment
		(start 144.875 84.5)
		(end 144.575 84.2)
		(width 0.1)
		(layer "F.Cu")
		(net 36)
	)
	(segment
		(start 155.855 80.88)
		(end 155.286 80.88)
		(width 0.1)
		(layer "F.Cu")
		(net 36)
	)
	(segment
		(start 148.325 90.35)
		(end 148.575 90.1)
		(width 0.1)
		(layer "F.Cu")
		(net 36)
	)
	(segment
		(start 145.775 91)
		(end 145.875 91)
		(width 0.1)
		(layer "F.Cu")
		(net 36)
	)
	(segment
		(start 153.476 95.724)
		(end 153.476 95.208)
		(width 0.2)
		(layer "F.Cu")
		(net 36)
	)
	(segment
		(start 152.175 87.75)
		(end 152.275 87.75)
		(width 0.1)
		(layer "F.Cu")
		(net 36)
	)
	(segment
		(start 152.175 93.846)
		(end 152.487 94.158)
		(width 0.1)
		(layer "F.Cu")
		(net 36)
	)
	(segment
		(start 151.375 85.15)
		(end 151.24333 85.15)
		(width 0.1)
		(layer "F.Cu")
		(net 36)
	)
	(segment
		(start 143.575 83.2)
		(end 143.445 83.07)
		(width 0.1)
		(layer "F.Cu")
		(net 36)
	)
	(segment
		(start 151.025 94.845)
		(end 150.901 94.969)
		(width 0.2)
		(layer "F.Cu")
		(net 36)
	)
	(segment
		(start 108.925 98.7)
		(end 108.925 97.15)
		(width 0.2)
		(layer "F.Cu")
		(net 36)
	)
	(segment
		(start 145.775 85.15)
		(end 145.64333 85.15)
		(width 0.1)
		(layer "F.Cu")
		(net 36)
	)
	(segment
		(start 155.925 97)
		(end 156.525 96.4)
		(width 0.2)
		(layer "F.Cu")
		(net 36)
	)
	(segment
		(start 145.875 81.25)
		(end 146.175 81.55)
		(width 0.1)
		(layer "F.Cu")
		(net 36)
	)
	(segment
		(start 143.875 87.45)
		(end 144.575 87.45)
		(width 0.1)
		(layer "F.Cu")
		(net 36)
	)
	(segment
		(start 154.125 90.35)
		(end 154.325 90.15)
		(width 0.1)
		(layer "F.Cu")
		(net 36)
	)
	(segment
		(start 153.775 91.65)
		(end 153.475 91.35)
		(width 0.1)
		(layer "F.Cu")
		(net 36)
	)
	(segment
		(start 143.27499 96.74999)
		(end 143.425 96.9)
		(width 0.2)
		(layer "F.Cu")
		(net 36)
	)
	(segment
		(start 108.425 97.25)
		(end 108.675 97)
		(width 0.2)
		(layer "F.Cu")
		(net 36)
	)
	(segment
		(start 150.575 80.65)
		(end 150.525 80.65)
		(width 0.1)
		(layer "F.Cu")
		(net 36)
	)
	(segment
		(start 153.775 91.65)
		(end 154.747 91.65)
		(width 0.1)
		(layer "F.Cu")
		(net 36)
	)
	(segment
		(start 102.675 96.5)
		(end 102.675 97.1)
		(width 0.2)
		(layer "F.Cu")
		(net 36)
	)
	(segment
		(start 150.325 90.1)
		(end 150.575 90.35)
		(width 0.1)
		(layer "F.Cu")
		(net 36)
	)
	(segment
		(start 148.275 79.3)
		(end 148.575 79.6)
		(width 0.1)
		(layer "F.Cu")
		(net 36)
	)
	(segment
		(start 143.445 83.07)
		(end 142.925 83.07)
		(width 0.1)
		(layer "F.Cu")
		(net 36)
	)
	(segment
		(start 110.425 97.2)
		(end 110.675 96.95)
		(width 0.2)
		(layer "F.Cu")
		(net 36)
	)
	(segment
		(start 128.025 91.15)
		(end 127.15 91.15)
		(width 0.2)
		(layer "F.Cu")
		(net 36)
	)
	(segment
		(start 144.675 91.65)
		(end 144.395 91.37)
		(width 0.1)
		(layer "F.Cu")
		(net 36)
	)
	(segment
		(start 147.475 91)
		(end 147.775 91.3)
		(width 0.1)
		(layer "F.Cu")
		(net 36)
	)
	(segment
		(start 147.075 93.45)
		(end 147.075008 93.45)
		(width 0.1)
		(layer "F.Cu")
		(net 36)
	)
	(segment
		(start 148.275 80.6)
		(end 148.575 80.9)
		(width 0.1)
		(layer "F.Cu")
		(net 36)
	)
	(segment
		(start 122.27501 87.175)
		(end 121.13 87.175)
		(width 0.2)
		(layer "F.Cu")
		(net 36)
	)
	(segment
		(start 153.475 91.35)
		(end 153.325 91.35)
		(width 0.1)
		(layer "F.Cu")
		(net 36)
	)
	(segment
		(start 142.925 87.28)
		(end 143.705 87.28)
		(width 0.1)
		(layer "F.Cu")
		(net 36)
	)
	(segment
		(start 154.347 83.2)
		(end 154.394 83.153)
		(width 0.1)
		(layer "F.Cu")
		(net 36)
	)
	(segment
		(start 153.775 81.9)
		(end 154.394 81.9)
		(width 0.1)
		(layer "F.Cu")
		(net 36)
	)
	(segment
		(start 107.725 97)
		(end 107.725 96.5)
		(width 0.2)
		(layer "F.Cu")
		(net 36)
	)
	(segment
		(start 155.925 98.7)
		(end 155.925 97)
		(width 0.2)
		(layer "F.Cu")
		(net 36)
	)
	(segment
		(start 110.425 98.65)
		(end 110.425 97.2)
		(width 0.2)
		(layer "F.Cu")
		(net 36)
	)
	(segment
		(start 152.175 84.5)
		(end 152.275 84.5)
		(width 0.1)
		(layer "F.Cu")
		(net 36)
	)
	(segment
		(start 143.425 96.9)
		(end 143.425 98.7)
		(width 0.2)
		(layer "F.Cu")
		(net 36)
	)
	(segment
		(start 146.575 83.2)
		(end 146.675 83.2)
		(width 0.1)
		(layer "F.Cu")
		(net 36)
	)
	(segment
		(start 130.725 90.2)
		(end 131.585 90.2)
		(width 0.2)
		(layer "F.Cu")
		(net 36)
	)
	(segment
		(start 150.575 91.65)
		(end 150.925 91.3)
		(width 0.1)
		(layer "F.Cu")
		(net 36)
	)
	(segment
		(start 102.675 97.1)
		(end 102.425 97.35)
		(width 0.2)
		(layer "F.Cu")
		(net 36)
	)
	(segment
		(start 155.295 87.88)
		(end 155.855 87.88)
		(width 0.1)
		(layer "F.Cu")
		(net 36)
	)
	(segment
		(start 150.575 89.05)
		(end 150.525 89.05)
		(width 0.1)
		(layer "F.Cu")
		(net 36)
	)
	(segment
		(start 148.125 91.65)
		(end 147.775 91.3)
		(width 0.1)
		(layer "F.Cu")
		(net 36)
	)
	(segment
		(start 130.725 90.2)
		(end 130.725 88.8992)
		(width 0.2)
		(layer "F.Cu")
		(net 36)
	)
	(segment
		(start 147.475 81.25)
		(end 147.775 81.55)
		(width 0.1)
		(layer "F.Cu")
		(net 36)
	)
	(segment
		(start 105.425 98.75)
		(end 105.425 97.3)
		(width 0.2)
		(layer "F.Cu")
		(net 36)
	)
	(segment
		(start 151.375 87.1)
		(end 151.275 87.1)
		(width 0.1)
		(layer "F.Cu")
		(net 36)
	)
	(segment
		(start 102.925 98.7)
		(end 102.925 97.15)
		(width 0.2)
		(layer "F.Cu")
		(net 36)
	)
	(segment
		(start 154.747 91.65)
		(end 155.117 92.02)
		(width 0.1)
		(layer "F.Cu")
		(net 36)
	)
	(segment
		(start 150.525 81.9)
		(end 150.17502 82.24998)
		(width 0.1)
		(layer "F.Cu")
		(net 36)
	)
	(segment
		(start 105.925 98.75)
		(end 105.925 97.2)
		(width 0.2)
		(layer "F.Cu")
		(net 36)
	)
	(segment
		(start 155.117 92.02)
		(end 155.855 92.02)
		(width 0.1)
		(layer "F.Cu")
		(net 36)
	)
	(segment
		(start 145.32498 90.69998)
		(end 144.975 90.35)
		(width 0.1)
		(layer "F.Cu")
		(net 36)
	)
	(segment
		(start 131.145 81.845)
		(end 131.15 81.85)
		(width 0.2)
		(layer "F.Cu")
		(net 36)
	)
	(segment
		(start 106.975 98.7)
		(end 106.975 97.15)
		(width 0.2)
		(layer "F.Cu")
		(net 36)
	)
	(segment
		(start 104.425 98.75)
		(end 104.425 97.3)
		(width 0.2)
		(layer "F.Cu")
		(net 36)
	)
	(segment
		(start 144.975 89.05)
		(end 145.295 89.37)
		(width 0.1)
		(layer "F.Cu")
		(net 36)
	)
	(segment
		(start 152.175 89.05)
		(end 152.125 89.05)
		(width 0.1)
		(layer "F.Cu")
		(net 36)
	)
	(segment
		(start 154.705 89.05)
		(end 153.775 89.05)
		(width 0.1)
		(layer "F.Cu")
		(net 36)
	)
	(segment
		(start 145.875 91)
		(end 146.175 91.3)
		(width 0.1)
		(layer "F.Cu")
		(net 36)
	)
	(segment
		(start 150.075 90.1)
		(end 150.325 90.1)
		(width 0.1)
		(layer "F.Cu")
		(net 36)
	)
	(segment
		(start 152.175 92.95)
		(end 152.175 93.846)
		(width 0.1)
		(layer "F.Cu")
		(net 36)
	)
	(segment
		(start 145.47498 90.69998)
		(end 145.775 91)
		(width 0.1)
		(layer "F.Cu")
		(net 36)
	)
	(segment
		(start 104.425 97.3)
		(end 104.675 97.05)
		(width 0.2)
		(layer "F.Cu")
		(net 36)
	)
	(segment
		(start 148.175 81.9)
		(end 148.275 81.9)
		(width 0.1)
		(layer "F.Cu")
		(net 36)
	)
	(segment
		(start 155.006 80.6)
		(end 153.775 80.6)
		(width 0.1)
		(layer "F.Cu")
		(net 36)
	)
	(segment
		(start 102.925 97.15)
		(end 103.175 96.9)
		(width 0.2)
		(layer "F.Cu")
		(net 36)
	)
	(segment
		(start 146.255 89.37)
		(end 146.575 89.05)
		(width 0.1)
		(layer "F.Cu")
		(net 36)
	)
	(segment
		(start 145.375 90.69998)
		(end 145.32498 90.69998)
		(width 0.1)
		(layer "F.Cu")
		(net 36)
	)
	(segment
		(start 111.425 97.2)
		(end 111.675 96.95)
		(width 0.2)
		(layer "F.Cu")
		(net 36)
	)
	(segment
		(start 108.675 97)
		(end 108.675 96.5)
		(width 0.2)
		(layer "F.Cu")
		(net 36)
	)
	(segment
		(start 109.425 98.65)
		(end 109.425 97.2)
		(width 0.2)
		(layer "F.Cu")
		(net 36)
	)
	(segment
		(start 144.975 81.9)
		(end 144.155 81.9)
		(width 0.1)
		(layer "F.Cu")
		(net 36)
	)
	(segment
		(start 152.275 83.2)
		(end 152.575 83.5)
		(width 0.1)
		(layer "F.Cu")
		(net 36)
	)
	(segment
		(start 142.275 83.07)
		(end 142.925 83.07)
		(width 0.2)
		(layer "F.Cu")
		(net 36)
	)
	(segment
		(start 144.155 81.9)
		(end 143.825 81.57)
		(width 0.1)
		(layer "F.Cu")
		(net 36)
	)
	(segment
		(start 152.175 78.45)
		(end 152.095 78.37)
		(width 0.1)
		(layer "F.Cu")
		(net 36)
	)
	(segment
		(start 151.025 94.45)
		(end 151.025 94.845)
		(width 0.2)
		(layer "F.Cu")
		(net 36)
	)
	(segment
		(start 151.24333 85.15)
		(end 150.98628 85.40705)
		(width 0.1)
		(layer "F.Cu")
		(net 36)
	)
	(segment
		(start 152.275 87.75)
		(end 152.575 88.05)
		(width 0.1)
		(layer "F.Cu")
		(net 36)
	)
	(segment
		(start 150.925 91.3)
		(end 151.075 91.3)
		(width 0.1)
		(layer "F.Cu")
		(net 36)
	)
	(segment
		(start 151.275 87.1)
		(end 150.975 86.8)
		(width 0.1)
		(layer "F.Cu")
		(net 36)
	)
	(segment
		(start 146.575 84.5)
		(end 146.675 84.5)
		(width 0.1)
		(layer "F.Cu")
		(net 36)
	)
	(segment
		(start 106.725 97)
		(end 106.725 96.5)
		(width 0.2)
		(layer "F.Cu")
		(net 36)
	)
	(segment
		(start 103.675 97)
		(end 103.675 96.5)
		(width 0.2)
		(layer "F.Cu")
		(net 36)
	)
	(segment
		(start 154.175 88.05)
		(end 155.125 88.05)
		(width 0.1)
		(layer "F.Cu")
		(net 36)
	)
	(segment
		(start 142.925 88.78)
		(end 143.955 88.78)
		(width 0.1)
		(layer "F.Cu")
		(net 36)
	)
	(segment
		(start 153.476 95.208)
		(end 153.159 94.891)
		(width 0.2)
		(layer "F.Cu")
		(net 36)
	)
	(segment
		(start 148.275 81.9)
		(end 148.575 82.2)
		(width 0.1)
		(layer "F.Cu")
		(net 36)
	)
	(segment
		(start 146.675 83.2)
		(end 146.975 83.5)
		(width 0.1)
		(layer "F.Cu")
		(net 36)
	)
	(segment
		(start 101.925 98.7)
		(end 101.925 97.15)
		(width 0.2)
		(layer "F.Cu")
		(net 36)
	)
	(segment
		(start 150.525 83.2)
		(end 150.17502 83.54998)
		(width 0.1)
		(layer "F.Cu")
		(net 36)
	)
	(segment
		(start 153.475 95.725)
		(end 153.476 95.724)
		(width 0.2)
		(layer "F.Cu")
		(net 36)
	)
	(segment
		(start 155.855 85.22)
		(end 155.855 85.893)
		(width 0.2)
		(layer "F.Cu")
		(net 36)
	)
	(segment
		(start 153.775 90.35)
		(end 154.125 90.35)
		(width 0.1)
		(layer "F.Cu")
		(net 36)
	)
	(segment
		(start 153.325 91.35)
		(end 152.975 91)
		(width 0.1)
		(layer "F.Cu")
		(net 36)
	)
	(segment
		(start 147.375 91)
		(end 147.475 91)
		(width 0.1)
		(layer "F.Cu")
		(net 36)
	)
	(segment
		(start 103.425 98.7)
		(end 103.425 97.25)
		(width 0.2)
		(layer "F.Cu")
		(net 36)
	)
	(segment
		(start 110.675 96.95)
		(end 110.675 96.45)
		(width 0.2)
		(layer "F.Cu")
		(net 36)
	)
	(segment
		(start 132.175 91.13)
		(end 132.175 90.445)
		(width 0.2)
		(layer "F.Cu")
		(net 36)
	)
	(segment
		(start 103.425 97.25)
		(end 103.675 97)
		(width 0.2)
		(layer "F.Cu")
		(net 36)
	)
	(segment
		(start 110.925 97.1)
		(end 111.175 96.85)
		(width 0.2)
		(layer "F.Cu")
		(net 36)
	)
	(segment
		(start 111.675 96.95)
		(end 111.675 96.45)
		(width 0.2)
		(layer "F.Cu")
		(net 36)
	)
	(segment
		(start 142.625 91.37)
		(end 143.295 91.37)
		(width 0.2)
		(layer "F.Cu")
		(net 36)
	)
	(segment
		(start 150.575 83.2)
		(end 150.525 83.2)
		(width 0.1)
		(layer "F.Cu")
		(net 36)
	)
	(segment
		(start 152.487 94.158)
		(end 152.487 94.891)
		(width 0.1)
		(layer "F.Cu")
		(net 36)
	)
	(segment
		(start 108.925 97.15)
		(end 109.175 96.9)
		(width 0.2)
		(layer "F.Cu")
		(net 36)
	)
	(segment
		(start 151.075 91.3)
		(end 151.375 91)
		(width 0.1)
		(layer "F.Cu")
		(net 36)
	)
	(segment
		(start 152.275 84.5)
		(end 152.575 84.8)
		(width 0.1)
		(layer "F.Cu")
		(net 36)
	)
	(segment
		(start 155.286 80.88)
		(end 155.006 80.6)
		(width 0.1)
		(layer "F.Cu")
		(net 36)
	)
	(segment
		(start 146.575 92.95)
		(end 147.075 93.45)
		(width 0.1)
		(layer "F.Cu")
		(net 36)
	)
	(segment
		(start 154.874 82.38)
		(end 154.394 81.9)
		(width 0.1)
		(layer "F.Cu")
		(net 36)
	)
	(segment
		(start 107.975 97.15)
		(end 108.225 96.9)
		(width 0.2)
		(layer "F.Cu")
		(net 36)
	)
	(segment
		(start 103.925 98.7)
		(end 103.925 97.15)
		(width 0.2)
		(layer "F.Cu")
		(net 36)
	)
	(segment
		(start 150.525 80.65)
		(end 150.17502 80.99998)
		(width 0.1)
		(layer "F.Cu")
		(net 36)
	)
	(segment
		(start 146.931 93.594008)
		(end 147.075008 93.45)
		(width 0.2)
		(layer "F.Cu")
		(net 36)
	)
	(segment
		(start 109.925 98.65)
		(end 109.925 97.1)
		(width 0.2)
		(layer "F.Cu")
		(net 36)
	)
	(segment
		(start 108.425 98.7)
		(end 108.425 97.25)
		(width 0.2)
		(layer "F.Cu")
		(net 36)
	)
	(segment
		(start 142.055 88.78)
		(end 142.925 88.78)
		(width 0.2)
		(layer "F.Cu")
		(net 36)
	)
	(segment
		(start 153.159 94.891)
		(end 152.487 94.891)
		(width 0.2)
		(layer "F.Cu")
		(net 36)
	)
	(segment
		(start 130.725 88.8992)
		(end 131.125 88.4992)
		(width 0.2)
		(layer "F.Cu")
		(net 36)
	)
	(segment
		(start 107.975 98.7)
		(end 107.975 97.15)
		(width 0.2)
		(layer "F.Cu")
		(net 36)
	)
	(segment
		(start 112.675 96.95)
		(end 112.675 96.45)
		(width 0.2)
		(layer "F.Cu")
		(net 36)
	)
	(segment
		(start 144.975 84.5)
		(end 144.875 84.5)
		(width 0.1)
		(layer "F.Cu")
		(net 36)
	)
	(segment
		(start 104.675 97.05)
		(end 104.675 96.55)
		(width 0.2)
		(layer "F.Cu")
		(net 36)
	)
	(segment
		(start 103.925 97.15)
		(end 104.175 96.9)
		(width 0.2)
		(layer "F.Cu")
		(net 36)
	)
	(segment
		(start 110.925 98.65)
		(end 110.925 97.1)
		(width 0.2)
		(layer "F.Cu")
		(net 36)
	)
	(segment
		(start 144.575 84.2)
		(end 143.775 84.2)
		(width 0.1)
		(layer "F.Cu")
		(net 36)
	)
	(segment
		(start 143.775 84.2)
		(end 143.405 84.57)
		(width 0.1)
		(layer "F.Cu")
		(net 36)
	)
	(segment
		(start 148.175 79.3)
		(end 148.275 79.3)
		(width 0.1)
		(layer "F.Cu")
		(net 36)
	)
	(segment
		(start 143.405 84.57)
		(end 142.925 84.57)
		(width 0.1)
		(layer "F.Cu")
		(net 36)
	)
	(segment
		(start 104.925 97.2)
		(end 105.175 96.95)
		(width 0.2)
		(layer "F.Cu")
		(net 36)
	)
	(segment
		(start 111.425 98.65)
		(end 111.425 97.2)
		(width 0.2)
		(layer "F.Cu")
		(net 36)
	)
	(segment
		(start 101.925 97.15)
		(end 102.175 96.9)
		(width 0.2)
		(layer "F.Cu")
		(net 36)
	)
	(segment
		(start 123.245 81.545)
		(end 123.245 82.17)
		(width 0.2)
		(layer "F.Cu")
		(net 36)
	)
	(segment
		(start 112.425 97.2)
		(end 112.675 96.95)
		(width 0.2)
		(layer "F.Cu")
		(net 36)
	)
	(segment
		(start 104.925 98.75)
		(end 104.925 97.2)
		(width 0.2)
		(layer "F.Cu")
		(net 36)
	)
	(segment
		(start 105.425 97.3)
		(end 105.675 97.05)
		(width 0.2)
		(layer "F.Cu")
		(net 36)
	)
	(segment
		(start 147.425 98.7)
		(end 147.425 96.325)
		(width 0.2)
		(layer "F.Cu")
		(net 36)
	)
	(segment
		(start 106.475 97.25)
		(end 106.725 97)
		(width 0.2)
		(layer "F.Cu")
		(net 36)
	)
	(segment
		(start 148.175 80.6)
		(end 148.275 80.6)
		(width 0.1)
		(layer "F.Cu")
		(net 36)
	)
	(segment
		(start 148.175 91.65)
		(end 148.125 91.65)
		(width 0.1)
		(layer "F.Cu")
		(net 36)
	)
	(segment
		(start 107.475 98.7)
		(end 107.475 97.25)
		(width 0.2)
		(layer "F.Cu")
		(net 36)
	)
	(segment
		(start 148.175 90.35)
		(end 148.325 90.35)
		(width 0.1)
		(layer "F.Cu")
		(net 36)
	)
	(segment
		(start 152.175 83.2)
		(end 152.275 83.2)
		(width 0.1)
		(layer "F.Cu")
		(net 36)
	)
	(segment
		(start 153.775 83.2)
		(end 154.347 83.2)
		(width 0.1)
		(layer "F.Cu")
		(net 36)
	)
	(segment
		(start 105.675 97.05)
		(end 105.675 96.55)
		(width 0.2)
		(layer "F.Cu")
		(net 36)
	)
	(segment
		(start 134.175 84.715)
		(end 134.175 83.965)
		(width 0.2)
		(layer "F.Cu")
		(net 36)
	)
	(segment
		(start 155.085 89.43)
		(end 154.705 89.05)
		(width 0.1)
		(layer "F.Cu")
		(net 36)
	)
	(segment
		(start 145.295 89.37)
		(end 146.255 89.37)
		(width 0.1)
		(layer "F.Cu")
		(net 36)
	)
	(segment
		(start 155.125 88.05)
		(end 155.295 87.88)
		(width 0.1)
		(layer "F.Cu")
		(net 36)
	)
	(segment
		(start 133.075 72.15)
		(end 132.205 72.15)
		(width 0.2)
		(layer "F.Cu")
		(net 36)
	)
	(segment
		(start 146.931 94.861)
		(end 146.931 93.594008)
		(width 0.2)
		(layer "F.Cu")
		(net 36)
	)
	(segment
		(start 155.855 82.38)
		(end 154.874 82.38)
		(width 0.1)
		(layer "F.Cu")
		(net 36)
	)
	(segment
		(start 146.575 77.48)
		(end 146.605 77.45)
		(width 0.1)
		(layer "F.Cu")
		(net 36)
	)
	(segment
		(start 145.375 90.69998)
		(end 145.47498 90.69998)
		(width 0.1)
		(layer "F.Cu")
		(net 36)
	)
	(segment
		(start 144.395 91.37)
		(end 143.295 91.37)
		(width 0.1)
		(layer "F.Cu")
		(net 36)
	)
	(segment
		(start 152.175 78.8)
		(end 152.175 78.45)
		(width 0.1)
		(layer "F.Cu")
		(net 36)
	)
	(segment
		(start 147.375 85.15)
		(end 147.24333 85.15)
		(width 0.1)
		(layer "F.Cu")
		(net 36)
	)
	(segment
		(start 105.925 97.2)
		(end 106.175 96.95)
		(width 0.2)
		(layer "F.Cu")
		(net 36)
	)
	(segment
		(start 147.375 81.25)
		(end 147.475 81.25)
		(width 0.1)
		(layer "F.Cu")
		(net 36)
	)
	(segment
		(start 131.145 81.15)
		(end 131.145 81.845)
		(width 0.2)
		(layer "F.Cu")
		(net 36)
	)
	(segment
		(start 101.675 97)
		(end 101.675 96.5)
		(width 0.2)
		(layer "F.Cu")
		(net 36)
	)
	(segment
		(start 143.955 88.78)
		(end 144.225 89.05)
		(width 0.1)
		(layer "F.Cu")
		(net 36)
	)
	(segment
		(start 109.425 97.2)
		(end 109.675 96.95)
		(width 0.2)
		(layer "F.Cu")
		(net 36)
	)
	(segment
		(start 131.258332 72.15)
		(end 130.34 72.15)
		(width 0.2)
		(layer "F.Cu")
		(net 36)
	)
	(segment
		(start 107.475 97.25)
		(end 107.725 97)
		(width 0.2)
		(layer "F.Cu")
		(net 36)
	)
	(segment
		(start 129.441666 72.15)
		(end 128.535 72.15)
		(width 0.2)
		(layer "F.Cu")
		(net 36)
	)
	(segment
		(start 155.425 92.88)
		(end 155.855 92.88)
		(width 0.2)
		(layer "F.Cu")
		(net 36)
	)
	(segment
		(start 146.675 84.5)
		(end 146.975 84.8)
		(width 0.1)
		(layer "F.Cu")
		(net 36)
	)
	(segment
		(start 155.855 89.43)
		(end 155.085 89.43)
		(width 0.2)
		(layer "F.Cu")
		(net 36)
	)
	(segment
		(start 102.425 98.7)
		(end 102.425 97.35)
		(width 0.2)
		(layer "F.Cu")
		(net 36)
	)
	(segment
		(start 145.675 87.1)
		(end 145.375 86.8)
		(width 0.1)
		(layer "F.Cu")
		(net 36)
	)
	(segment
		(start 143.295 91.37)
		(end 143.275 91.35)
		(width 0.1)
		(layer "F.Cu")
		(net 36)
	)
	(segment
		(start 147.24333 85.15)
		(end 146.98628 85.40705)
		(width 0.1)
		(layer "F.Cu")
		(net 36)
	)
	(segment
		(start 150.575 81.9)
		(end 150.525 81.9)
		(width 0.1)
		(layer "F.Cu")
		(net 36)
	)
	(segment
		(start 127.625 72.15)
		(end 126.775 72.15)
		(width 0.2)
		(layer "F.Cu")
		(net 36)
	)
	(via
		(at 151.925 96.825)
		(size 0.4)
		(drill 0.15)
		(layers "F.Cu" "B.Cu")
		(net 36)
	)
	(via
		(at 148.575 90.1)
		(size 0.4)
		(drill 0.15)
		(layers "F.Cu" "B.Cu")
		(net 36)
	)
	(via
		(at 146.975 86.8)
		(size 0.4)
		(drill 0.15)
		(layers "F.Cu" "B.Cu")
		(net 36)
	)
	(via
		(at 152.58628 85.40705)
		(size 0.4)
		(drill 0.15)
		(layers "F.Cu" "B.Cu")
		(net 36)
	)
	(via
		(at 152.575 86.8)
		(size 0.4)
		(drill 0.15)
		(layers "F.Cu" "B.Cu")
		(net 36)
	)
	(via
		(at 144.575 87.45)
		(size 0.4)
		(drill 0.15)
		(layers "F.Cu" "B.Cu")
		(net 36)
	)
	(via
		(at 146.175 87.45)
		(size 0.4)
		(drill 0.15)
		(layers "F.Cu" "B.Cu")
		(net 36)
	)
	(via
		(at 154.175 88.05)
		(size 0.4)
		(drill 0.15)
		(layers "F.Cu" "B.Cu")
		(net 36)
	)
	(via
		(at 144.575 80.3)
		(size 0.4)
		(drill 0.15)
		(layers "F.Cu" "B.Cu")
		(net 36)
	)
	(via
		(at 148.575 83.5)
		(size 0.4)
		(drill 0.15)
		(layers "F.Cu" "B.Cu")
		(net 36)
	)
	(via
		(at 153.375 81.55)
		(size 0.4)
		(drill 0.15)
		(layers "F.Cu" "B.Cu")
		(net 36)
	)
	(via
		(at 150.175 79.64998)
		(size 0.4)
		(drill 0.15)
		(layers "F.Cu" "B.Cu")
		(net 36)
	)
	(via
		(at 146.575 78.8)
		(size 0.4)
		(drill 0.15)
		(layers "F.Cu" "B.Cu")
		(net 36)
	)
	(via
		(at 152.175 78.8)
		(size 0.4)
		(drill 0.15)
		(layers "F.Cu" "B.Cu")
		(net 36)
	)
	(via
		(at 154.175 84.8)
		(size 0.4)
		(drill 0.15)
		(layers "F.Cu" "B.Cu")
		(net 36)
	)
	(via
		(at 151.775 81.55)
		(size 0.4)
		(drill 0.15)
		(layers "F.Cu" "B.Cu")
		(net 36)
	)
	(via
		(at 150.175 88.75)
		(size 0.4)
		(drill 0.15)
		(layers "F.Cu" "B.Cu")
		(net 36)
	)
	(via
		(at 148.575 88.7)
		(size 0.4)
		(drill 0.15)
		(layers "F.Cu" "B.Cu")
		(net 36)
	)
	(via
		(at 151.775 91.3)
		(size 0.4)
		(drill 0.15)
		(layers "F.Cu" "B.Cu")
		(net 36)
	)
	(via
		(at 154.394 81.9)
		(size 0.4)
		(drill 0.15)
		(layers "F.Cu" "B.Cu")
		(net 36)
	)
	(via
		(at 153.475 95.725)
		(size 0.4)
		(drill 0.15)
		(layers "F.Cu" "B.Cu")
		(net 36)
	)
	(via
		(at 155.975 95.775)
		(size 0.4)
		(drill 0.15)
		(layers "F.Cu" "B.Cu")
		(net 36)
	)
	(via
		(at 113.175 96.85)
		(size 0.5)
		(drill 0.15)
		(layers "F.Cu" "B.Cu")
		(net 36)
	)
	(via
		(at 113.675 96.45)
		(size 0.5)
		(drill 0.15)
		(layers "F.Cu" "B.Cu")
		(net 36)
	)
	(via
		(at 152.575 83.5)
		(size 0.4)
		(drill 0.15)
		(layers "F.Cu" "B.Cu")
		(net 36)
	)
	(via
		(at 131.875 83.55)
		(size 0.5)
		(drill 0.15)
		(layers "F.Cu" "B.Cu")
		(net 36)
	)
	(via
		(at 143.27499 96.325)
		(size 0.4)
		(drill 0.15)
		(layers "F.Cu" "B.Cu")
		(net 36)
	)
	(via
		(at 109.175 96.9)
		(size 0.5)
		(drill 0.15)
		(layers "F.Cu" "B.Cu")
		(net 36)
	)
	(via
		(at 144.575 84.2)
		(size 0.4)
		(drill 0.15)
		(layers "F.Cu" "B.Cu")
		(net 36)
	)
	(via
		(at 143.825 81.57)
		(size 0.4)
		(drill 0.15)
		(layers "F.Cu" "B.Cu")
		(net 36)
	)
	(via
		(at 150.98628 85.40705)
		(size 0.4)
		(drill 0.15)
		(layers "F.Cu" "B.Cu")
		(net 36)
	)
	(via
		(at 109.675 96.45)
		(size 0.5)
		(drill 0.15)
		(layers "F.Cu" "B.Cu")
		(net 36)
	)
	(via
		(at 147.775 91.3)
		(size 0.4)
		(drill 0.15)
		(layers "F.Cu" "B.Cu")
		(net 36)
	)
	(via
		(at 147.775 81.55)
		(size 0.4)
		(drill 0.15)
		(layers "F.Cu" "B.Cu")
		(net 36)
	)
	(via
		(at 111.175 96.85)
		(size 0.5)
		(drill 0.15)
		(layers "F.Cu" "B.Cu")
		(net 36)
	)
	(via
		(at 154.325 90.15)
		(size 0.4)
		(drill 0.15)
		(layers "F.Cu" "B.Cu")
		(net 36)
	)
	(via
		(at 152.575 84.8)
		(size 0.4)
		(drill 0.15)
		(layers "F.Cu" "B.Cu")
		(net 36)
	)
	(via
		(at 106.175 96.95)
		(size 0.5)
		(drill 0.15)
		(layers "F.Cu" "B.Cu")
		(net 36)
	)
	(via
		(at 148.575 80.9)
		(size 0.4)
		(drill 0.15)
		(layers "F.Cu" "B.Cu")
		(net 36)
	)
	(via
		(at 147.075008 93.45)
		(size 0.4)
		(drill 0.15)
		(layers "F.Cu" "B.Cu")
		(net 36)
	)
	(via
		(at 147.425 96.325)
		(size 0.4)
		(drill 0.15)
		(layers "F.Cu" "B.Cu")
		(net 36)
	)
	(via
		(at 142.275 83.07)
		(size 0.5)
		(drill 0.15)
		(layers "F.Cu" "B.Cu")
		(net 36)
	)
	(via
		(at 146.975 83.5)
		(size 0.4)
		(drill 0.15)
		(layers "F.Cu" "B.Cu")
		(net 36)
	)
	(via
		(at 143.275 91.35)
		(size 0.4)
		(drill 0.15)
		(layers "F.Cu" "B.Cu")
		(net 36)
	)
	(via
		(at 155.425 92.02)
		(size 0.4)
		(drill 0.15)
		(layers "F.Cu" "B.Cu")
		(net 36)
	)
	(via
		(at 102.175 96.9)
		(size 0.5)
		(drill 0.15)
		(layers "F.Cu" "B.Cu")
		(net 36)
	)
	(via
		(at 150.175 83.54998)
		(size 0.4)
		(drill 0.15)
		(layers "F.Cu" "B.Cu")
		(net 36)
	)
	(via
		(at 105.675 96.55)
		(size 0.5)
		(drill 0.15)
		(layers "F.Cu" "B.Cu")
		(net 36)
	)
	(via
		(at 130.34 72.15)
		(size 0.4)
		(drill 0.15)
		(layers "F.Cu" "B.Cu")
		(net 36)
	)
	(via
		(at 155.425 92.88)
		(size 0.4)
		(drill 0.15)
		(layers "F.Cu" "B.Cu")
		(net 36)
	)
	(via
		(at 150.075 90.1)
		(size 0.4)
		(drill 0.15)
		(layers "F.Cu" "B.Cu")
		(net 36)
	)
	(via
		(at 150.175 80.99998)
		(size 0.4)
		(drill 0.15)
		(layers "F.Cu" "B.Cu")
		(net 36)
	)
	(via
		(at 111.675 96.45)
		(size 0.5)
		(drill 0.15)
		(layers "F.Cu" "B.Cu")
		(net 36)
	)
	(via
		(at 131.585 90.2)
		(size 0.4)
		(drill 0.15)
		(layers "F.Cu" "B.Cu")
		(net 36)
	)
	(via
		(at 146.975 84.8)
		(size 0.4)
		(drill 0.15)
		(layers "F.Cu" "B.Cu")
		(net 36)
	)
	(via
		(at 104.175 96.9)
		(size 0.5)
		(drill 0.15)
		(layers "F.Cu" "B.Cu")
		(net 36)
	)
	(via
		(at 150.175 82.24998)
		(size 0.4)
		(drill 0.15)
		(layers "F.Cu" "B.Cu")
		(net 36)
	)
	(via
		(at 102.675 96.5)
		(size 0.5)
		(drill 0.15)
		(layers "F.Cu" "B.Cu")
		(net 36)
	)
	(via
		(at 149.375 86.65)
		(size 0.4)
		(drill 0.15)
		(layers "F.Cu" "B.Cu")
		(net 36)
	)
	(via
		(at 145.375 90.69998)
		(size 0.4)
		(drill 0.15)
		(layers "F.Cu" "B.Cu")
		(net 36)
	)
	(via
		(at 145.38628 85.40705)
		(size 0.4)
		(drill 0.15)
		(layers "F.Cu" "B.Cu")
		(net 36)
	)
	(via
		(at 149.825 91.8)
		(size 0.4)
		(drill 0.15)
		(layers "F.Cu" "B.Cu")
		(net 36)
	)
	(via
		(at 110.675 96.45)
		(size 0.5)
		(drill 0.15)
		(layers "F.Cu" "B.Cu")
		(net 36)
	)
	(via
		(at 131.15 81.85)
		(size 0.4)
		(drill 0.15)
		(layers "F.Cu" "B.Cu")
		(net 36)
	)
	(via
		(at 107.225 96.9)
		(size 0.5)
		(drill 0.15)
		(layers "F.Cu" "B.Cu")
		(net 36)
	)
	(via
		(at 146.175 81.55)
		(size 0.4)
		(drill 0.15)
		(layers "F.Cu" "B.Cu")
		(net 36)
	)
	(via
		(at 151.025 94.45)
		(size 0.4)
		(drill 0.15)
		(layers "F.Cu" "B.Cu")
		(net 36)
	)
	(via
		(at 126.775 72.15)
		(size 0.4)
		(drill 0.15)
		(layers "F.Cu" "B.Cu")
		(net 36)
	)
	(via
		(at 148.575 79.6)
		(size 0.4)
		(drill 0.15)
		(layers "F.Cu" "B.Cu")
		(net 36)
	)
	(via
		(at 146.98628 85.40705)
		(size 0.4)
		(drill 0.15)
		(layers "F.Cu" "B.Cu")
		(net 36)
	)
	(via
		(at 127.15 91.15)
		(size 0.4)
		(drill 0.15)
		(layers "F.Cu" "B.Cu")
		(net 36)
	)
	(via
		(at 155.855 85.893)
		(size 0.5)
		(drill 0.15)
		(layers "F.Cu" "B.Cu")
		(net 36)
	)
	(via
		(at 154.394 83.153)
		(size 0.4)
		(drill 0.15)
		(layers "F.Cu" "B.Cu")
		(net 36)
	)
	(via
		(at 103.675 96.5)
		(size 0.5)
		(drill 0.15)
		(layers "F.Cu" "B.Cu")
		(net 36)
	)
	(via
		(at 112.675 96.45)
		(size 0.5)
		(drill 0.15)
		(layers "F.Cu" "B.Cu")
		(net 36)
	)
	(via
		(at 155.085 89.43)
		(size 0.4)
		(drill 0.15)
		(layers "F.Cu" "B.Cu")
		(net 36)
	)
	(via
		(at 112.175 96.85)
		(size 0.5)
		(drill 0.15)
		(layers "F.Cu" "B.Cu")
		(net 36)
	)
	(via
		(at 145.375 86.8)
		(size 0.4)
		(drill 0.15)
		(layers "F.Cu" "B.Cu")
		(net 36)
	)
	(via
		(at 150.975 86.8)
		(size 0.4)
		(drill 0.15)
		(layers "F.Cu" "B.Cu")
		(net 36)
	)
	(via
		(at 141.675 96.3)
		(size 0.5)
		(drill 0.15)
		(layers "F.Cu" "B.Cu")
		(net 36)
	)
	(via
		(at 152.575 88.05)
		(size 0.4)
		(drill 0.15)
		(layers "F.Cu" "B.Cu")
		(net 36)
	)
	(via
		(at 106.725 96.5)
		(size 0.5)
		(drill 0.15)
		(layers "F.Cu" "B.Cu")
		(net 36)
	)
	(via
		(at 132.205 72.15)
		(size 0.4)
		(drill 0.15)
		(layers "F.Cu" "B.Cu")
		(net 36)
	)
	(via
		(at 123.245 82.17)
		(size 0.4)
		(drill 0.15)
		(layers "F.Cu" "B.Cu")
		(net 36)
	)
	(via
		(at 107.725 96.5)
		(size 0.5)
		(drill 0.15)
		(layers "F.Cu" "B.Cu")
		(net 36)
	)
	(via
		(at 108.225 96.9)
		(size 0.5)
		(drill 0.15)
		(layers "F.Cu" "B.Cu")
		(net 36)
	)
	(via
		(at 151.775 89.4)
		(size 0.4)
		(drill 0.15)
		(layers "F.Cu" "B.Cu")
		(net 36)
	)
	(via
		(at 154.394 80.6)
		(size 0.4)
		(drill 0.15)
		(layers "F.Cu" "B.Cu")
		(net 36)
	)
	(via
		(at 142.055 88.78)
		(size 0.5)
		(drill 0.15)
		(layers "F.Cu" "B.Cu")
		(net 36)
	)
	(via
		(at 146.175 91.3)
		(size 0.4)
		(drill 0.15)
		(layers "F.Cu" "B.Cu")
		(net 36)
	)
	(via
		(at 121.13 87.175)
		(size 0.4)
		(drill 0.15)
		(layers "F.Cu" "B.Cu")
		(net 36)
	)
	(via
		(at 103.175 96.9)
		(size 0.5)
		(drill 0.15)
		(layers "F.Cu" "B.Cu")
		(net 36)
	)
	(via
		(at 108.675 96.5)
		(size 0.5)
		(drill 0.15)
		(layers "F.Cu" "B.Cu")
		(net 36)
	)
	(via
		(at 105.175 96.95)
		(size 0.5)
		(drill 0.15)
		(layers "F.Cu" "B.Cu")
		(net 36)
	)
	(via
		(at 156.525 96.4)
		(size 0.5)
		(drill 0.15)
		(layers "F.Cu" "B.Cu")
		(net 36)
	)
	(via
		(at 128.535 72.15)
		(size 0.4)
		(drill 0.15)
		(layers "F.Cu" "B.Cu")
		(net 36)
	)
	(via
		(at 134.175 83.965)
		(size 0.4)
		(drill 0.15)
		(layers "F.Cu" "B.Cu")
		(net 36)
	)
	(via
		(at 148.575 82.2)
		(size 0.4)
		(drill 0.15)
		(layers "F.Cu" "B.Cu")
		(net 36)
	)
	(via
		(at 101.675 96.5)
		(size 0.5)
		(drill 0.15)
		(layers "F.Cu" "B.Cu")
		(net 36)
	)
	(via
		(at 104.675 96.55)
		(size 0.5)
		(drill 0.15)
		(layers "F.Cu" "B.Cu")
		(net 36)
	)
	(via
		(at 110.175 96.85)
		(size 0.5)
		(drill 0.15)
		(layers "F.Cu" "B.Cu")
		(net 36)
	)
	(via
		(at 132.175 90.445)
		(size 0.4)
		(drill 0.15)
		(layers "F.Cu" "B.Cu")
		(net 36)
	)
	(segment
		(start 155.675 98.75)
		(end 155.675 97.4)
		(width 0.1)
		(layer "B.Cu")
		(net 36)
	)
	(segment
		(start 155.975 97.1)
		(end 155.975 95.75)
		(width 0.1)
		(layer "B.Cu")
		(net 36)
	)
	(segment
		(start 155.675 97.4)
		(end 155.975 97.1)
		(width 0.1)
		(layer "B.Cu")
		(net 36)
	)
	(segment
		(start 113.175 98.65)
		(end 113.175 96.85)
		(width 0.2)
		(layer "B.Cu")
		(net 36)
	)
	(segment
		(start 113.675 98.65)
		(end 113.675 96.45)
		(width 0.2)
		(layer "B.Cu")
		(net 36)
	)
	(segment
		(start 150.175 83.54998)
		(end 149.59498 84.13)
		(width 0.1)
		(layer "B.Cu")
		(net 36)
	)
	(segment
		(start 111.675 98.65)
		(end 111.675 96.45)
		(width 0.2)
		(layer "B.Cu")
		(net 36)
	)
	(segment
		(start 153.175 98.7)
		(end 153.175 97.069975)
		(width 0.1)
		(layer "B.Cu")
		(net 36)
	)
	(segment
		(start 151.055 85.47577)
		(end 150.98628 85.40705)
		(width 0.1)
		(layer "B.Cu")
		(net 36)
	)
	(segment
		(start 148.564975 95.97)
		(end 147.78 95.97)
		(width 0.1)
		(layer "B.Cu")
		(net 36)
	)
	(segment
		(start 103.175 98.7)
		(end 103.175 96.9)
		(width 0.2)
		(layer "B.Cu")
		(net 36)
	)
	(segment
		(start 145.175 97.080025)
		(end 146.295025 95.96)
		(width 0.1)
		(layer "B.Cu")
		(net 36)
	)
	(segment
		(start 146.905 81.55)
		(end 146.975 81.62)
		(width 0.1)
		(layer "B.Cu")
		(net 36)
	)
	(segment
		(start 109.675 98.65)
		(end 109.675 96.45)
		(width 0.2)
		(layer "B.Cu")
		(net 36)
	)
	(segment
		(start 147.06 95.96)
		(end 147.425 96.325)
		(width 0.1)
		(layer "B.Cu")
		(net 36)
	)
	(segment
		(start 149.275 97.03)
		(end 149.275 96.680025)
		(width 0.1)
		(layer "B.Cu")
		(net 36)
	)
	(segment
		(start 146.975 86.8)
		(end 146.975 86.18)
		(width 0.1)
		(layer "B.Cu")
		(net 36)
	)
	(segment
		(start 149.375 88.83)
		(end 150.095 88.83)
		(width 0.1)
		(layer "B.Cu")
		(net 36)
	)
	(segment
		(start 110.175 98.65)
		(end 110.175 96.85)
		(width 0.2)
		(layer "B.Cu")
		(net 36)
	)
	(segment
		(start 141.675 98.7)
		(end 141.675 96.3)
		(width 0.2)
		(layer "B.Cu")
		(net 36)
	)
	(segment
		(start 146.98628 86.00872)
		(end 146.895 86.1)
		(width 0.1)
		(layer "B.Cu")
		(net 36)
	)
	(segment
		(start 151.775 82.615)
		(end 151.775 81.55)
		(width 0.1)
		(layer "B.Cu")
		(net 36)
	)
	(segment
		(start 149.005 82.63)
		(end 148.575 82.2)
		(width 0.1)
		(layer "B.Cu")
		(net 36)
	)
	(segment
		(start 110.675 98.65)
		(end 110.675 96.45)
		(width 0.2)
		(layer "B.Cu")
		(net 36)
	)
	(segment
		(start 146.175 91.3)
		(end 146.413 91.3)
		(width 0.1)
		(layer "B.Cu")
		(net 36)
	)
	(segment
		(start 106.175 98.75)
		(end 106.175 96.95)
		(width 0.2)
		(layer "B.Cu")
		(net 36)
	)
	(segment
		(start 145.375 86.8)
		(end 145.375 86.18)
		(width 0.1)
		(layer "B.Cu")
		(net 36)
	)
	(segment
		(start 149.375 82.63)
		(end 149.005 82.63)
		(width 0.1)
		(layer "B.Cu")
		(net 36)
	)
	(segment
		(start 112.675 98.65)
		(end 112.675 96.45)
		(width 0.2)
		(layer "B.Cu")
		(net 36)
	)
	(segment
		(start 105.175 98.75)
		(end 105.175 96.95)
		(width 0.2)
		(layer "B.Cu")
		(net 36)
	)
	(segment
		(start 152.755 86.62)
		(end 152.575 86.8)
		(width 0.1)
		(layer "B.Cu")
		(net 36)
	)
	(segment
		(start 103.675 98.7)
		(end 103.675 96.5)
		(width 0.2)
		(layer "B.Cu")
		(net 36)
	)
	(segment
		(start 149.175 97.13)
		(end 149.275 97.03)
		(width 0.1)
		(layer "B.Cu")
		(net 36)
	)
	(segment
		(start 145.38628 86.00872)
		(end 145.295 86.1)
		(width 0.1)
		(layer "B.Cu")
		(net 36)
	)
	(segment
		(start 149.375 87.23)
		(end 149.375 86.65)
		(width 0.1)
		(layer "B.Cu")
		(net 36)
	)
	(segment
		(start 108.675 98.7)
		(end 108.675 96.5)
		(width 0.2)
		(layer "B.Cu")
		(net 36)
	)
	(segment
		(start 149.275 96.680025)
		(end 148.564975 95.97)
		(width 0.1)
		(layer "B.Cu")
		(net 36)
	)
	(segment
		(start 149.79498 82.63)
		(end 150.175 82.24998)
		(width 0.1)
		(layer "B.Cu")
		(net 36)
	)
	(segment
		(start 107.225 98.7)
		(end 107.225 96.9)
		(width 0.2)
		(layer "B.Cu")
		(net 36)
	)
	(segment
		(start 145.375 86.18)
		(end 145.295 86.1)
		(width 0.1)
		(layer "B.Cu")
		(net 36)
	)
	(segment
		(start 149.175 98.7)
		(end 149.175 97.13)
		(width 0.1)
		(layer "B.Cu")
		(net 36)
	)
	(segment
		(start 109.175 98.7)
		(end 109.175 96.9)
		(width 0.2)
		(layer "B.Cu")
		(net 36)
	)
	(segment
		(start 149.375 81.13)
		(end 148.805 81.13)
		(width 0.1)
		(layer "B.Cu")
		(net 36)
	)
	(segment
		(start 151.055 86.72)
		(end 150.975 86.8)
		(width 0.1)
		(layer "B.Cu")
		(net 36)
	)
	(segment
		(start 152.405 81.55)
		(end 152.575 81.72)
		(width 0.1)
		(layer "B.Cu")
		(net 36)
	)
	(segment
		(start 153.375 82.23)
		(end 153.375 81.55)
		(width 0.1)
		(layer "B.Cu")
		(net 36)
	)
	(segment
		(start 149.375 81.13)
		(end 150.04498 81.13)
		(width 0.1)
		(layer "B.Cu")
		(net 36)
	)
	(segment
		(start 102.175 98.7)
		(end 102.175 96.9)
		(width 0.2)
		(layer "B.Cu")
		(net 36)
	)
	(segment
		(start 149.825 91.8)
		(end 149.755 91.8)
		(width 0.1)
		(layer "B.Cu")
		(net 36)
	)
	(segment
		(start 153.175 97.069975)
		(end 153.775 96.469975)
		(width 0.1)
		(layer "B.Cu")
		(net 36)
	)
	(segment
		(start 152.755 86.15)
		(end 152.755 85.57577)
		(width 0.1)
		(layer "B.Cu")
		(net 36)
	)
	(segment
		(start 150.04498 81.13)
		(end 150.175 80.99998)
		(width 0.1)
		(layer "B.Cu")
		(net 36)
	)
	(segment
		(start 152.755 86.15)
		(end 152.755 86.62)
		(width 0.1)
		(layer "B.Cu")
		(net 36)
	)
	(segment
		(start 146.175 81.55)
		(end 146.905 81.55)
		(width 0.1)
		(layer "B.Cu")
		(net 36)
	)
	(segment
		(start 149.725 90.1)
		(end 150.075 90.1)
		(width 0.1)
		(layer "B.Cu")
		(net 36)
	)
	(segment
		(start 146.975 86.18)
		(end 146.895 86.1)
		(width 0.1)
		(layer "B.Cu")
		(net 36)
	)
	(segment
		(start 148.575 83.5)
		(end 149.205 84.13)
		(width 0.1)
		(layer "B.Cu")
		(net 36)
	)
	(segment
		(start 149.375 79.63)
		(end 150.15502 79.63)
		(width 0.1)
		(layer "B.Cu")
		(net 36)
	)
	(segment
		(start 149.345 79.6)
		(end 149.375 79.63)
		(width 0.1)
		(layer "B.Cu")
		(net 36)
	)
	(segment
		(start 111.175 98.65)
		(end 111.175 96.85)
		(width 0.2)
		(layer "B.Cu")
		(net 36)
	)
	(segment
		(start 148.805 81.13)
		(end 148.575 80.9)
		(width 0.1)
		(layer "B.Cu")
		(net 36)
	)
	(segment
		(start 107.725 98.7)
		(end 107.725 96.5)
		(width 0.2)
		(layer "B.Cu")
		(net 36)
	)
	(segment
		(start 146.98628 85.40705)
		(end 146.98628 86.00872)
		(width 0.1)
		(layer "B.Cu")
		(net 36)
	)
	(segment
		(start 149.375 82.63)
		(end 149.79498 82.63)
		(width 0.1)
		(layer "B.Cu")
		(net 36)
	)
	(segment
		(start 105.675 98.75)
		(end 105.675 96.55)
		(width 0.2)
		(layer "B.Cu")
		(net 36)
	)
	(segment
		(start 108.225 98.7)
		(end 108.225 96.9)
		(width 0.2)
		(layer "B.Cu")
		(net 36)
	)
	(segment
		(start 151.055 86.15)
		(end 151.055 85.47577)
		(width 0.1)
		(layer "B.Cu")
		(net 36)
	)
	(segment
		(start 150.15502 79.63)
		(end 150.175 79.64998)
		(width 0.1)
		(layer "B.Cu")
		(net 36)
	)
	(segment
		(start 151.775 81.55)
		(end 152.405 81.55)
		(width 0.1)
		(layer "B.Cu")
		(net 36)
	)
	(segment
		(start 153.775 96.025)
		(end 153.475 95.725)
		(width 0.1)
		(layer "B.Cu")
		(net 36)
	)
	(segment
		(start 149.375 86.65)
		(end 148.575 86.65)
		(width 0.1)
		(layer "B.Cu")
		(net 36)
	)
	(segment
		(start 145.38628 85.40705)
		(end 145.38628 86.00872)
		(width 0.1)
		(layer "B.Cu")
		(net 36)
	)
	(segment
		(start 146.275 83.42)
		(end 146.895 83.42)
		(width 0.1)
		(layer "B.Cu")
		(net 36)
	)
	(segment
		(start 153.775 96.469975)
		(end 153.775 96.025)
		(width 0.1)
		(layer "B.Cu")
		(net 36)
	)
	(segment
		(start 149.755 91.8)
		(end 149.375 92.18)
		(width 0.1)
		(layer "B.Cu")
		(net 36)
	)
	(segment
		(start 148.575 86.65)
		(end 148.395 86.47)
		(width 0.1)
		(layer "B.Cu")
		(net 36)
	)
	(segment
		(start 149.205 84.13)
		(end 149.375 84.13)
		(width 0.1)
		(layer "B.Cu")
		(net 36)
	)
	(segment
		(start 146.295025 95.96)
		(end 147.06 95.96)
		(width 0.1)
		(layer "B.Cu")
		(net 36)
	)
	(segment
		(start 106.725 98.7)
		(end 106.725 96.5)
		(width 0.2)
		(layer "B.Cu")
		(net 36)
	)
	(segment
		(start 145.175 98.7)
		(end 145.175 97.080025)
		(width 0.1)
		(layer "B.Cu")
		(net 36)
	)
	(segment
		(start 146.895 83.42)
		(end 146.975 83.5)
		(width 0.1)
		(layer "B.Cu")
		(net 36)
	)
	(segment
		(start 149.59498 84.13)
		(end 149.375 84.13)
		(width 0.1)
		(layer "B.Cu")
		(net 36)
	)
	(segment
		(start 152.755 85.57577)
		(end 152.58628 85.40705)
		(width 0.1)
		(layer "B.Cu")
		(net 36)
	)
	(segment
		(start 104.175 98.7)
		(end 104.175 96.9)
		(width 0.2)
		(layer "B.Cu")
		(net 36)
	)
	(segment
		(start 148.575 79.6)
		(end 149.345 79.6)
		(width 0.1)
		(layer "B.Cu")
		(net 36)
	)
	(segment
		(start 149.375 90.68)
		(end 149.375 90.45)
		(width 0.1)
		(layer "B.Cu")
		(net 36)
	)
	(segment
		(start 149.375 90.45)
		(end 149.725 90.1)
		(width 0.1)
		(layer "B.Cu")
		(net 36)
	)
	(segment
		(start 146.413 91.3)
		(end 146.803 91.69)
		(width 0.1)
		(layer "B.Cu")
		(net 36)
	)
	(segment
		(start 149.375 88.83)
		(end 148.705 88.83)
		(width 0.1)
		(layer "B.Cu")
		(net 36)
	)
	(segment
		(start 148.705 88.83)
		(end 148.575 88.7)
		(width 0.1)
		(layer "B.Cu")
		(net 36)
	)
	(segment
		(start 150.095 88.83)
		(end 150.175 88.75)
		(width 0.1)
		(layer "B.Cu")
		(net 36)
	)
	(segment
		(start 102.675 98.7)
		(end 102.675 96.5)
		(width 0.2)
		(layer "B.Cu")
		(net 36)
	)
	(segment
		(start 148.395 86.47)
		(end 148.395 86.1)
		(width 0.1)
		(layer "B.Cu")
		(net 36)
	)
	(segment
		(start 112.175 98.65)
		(end 112.175 96.85)
		(width 0.2)
		(layer "B.Cu")
		(net 36)
	)
	(segment
		(start 147.78 95.97)
		(end 147.425 96.325)
		(width 0.1)
		(layer "B.Cu")
		(net 36)
	)
	(segment
		(start 101.675 98.7)
		(end 101.675 96.5)
		(width 0.2)
		(layer "B.Cu")
		(net 36)
	)
	(segment
		(start 151.055 86.15)
		(end 151.055 86.72)
		(width 0.1)
		(layer "B.Cu")
		(net 36)
	)
	(segment
		(start 104.675 98.75)
		(end 104.675 96.55)
		(width 0.2)
		(layer "B.Cu")
		(net 36)
	)
	(segment
		(start 122.27501 86.525)
		(end 123.12501 86.525)
		(width 0.2)
		(layer "F.Cu")
		(net 151)
	)
	(segment
		(start 129.235 78.815)
		(end 131.85 78.815)
		(width 0.2)
		(layer "F.Cu")
		(net 151)
	)
	(segment
		(start 123.12501 86.525)
		(end 125.925 83.72501)
		(width 0.2)
		(layer "F.Cu")
		(net 151)
	)
	(segment
		(start 131.85 78.815)
		(end 133.075 77.59)
		(width 0.2)
		(layer "F.Cu")
		(net 151)
	)
	(segment
		(start 125.925 82.125)
		(end 129.235 78.815)
		(width 0.2)
		(layer "F.Cu")
		(net 151)
	)
	(segment
		(start 125.925 83.72501)
		(end 125.925 82.125)
		(width 0.2)
		(layer "F.Cu")
		(net 151)
	)
	(segment
		(start 133.075 77.59)
		(end 133.075 76.435)
		(width 0.2)
		(layer "F.Cu")
		(net 151)
	)
	(segment
		(start 127.975 88.4992)
		(end 127.975 87.175)
		(width 0.2)
		(layer "F.Cu")
		(net 152)
	)
	(segment
		(start 127.975 86.525)
		(end 129.055 86.525)
		(width 0.2)
		(layer "F.Cu")
		(net 153)
	)
	(segment
		(start 129.055 86.525)
		(end 129.55 87.02)
		(width 0.2)
		(layer "F.Cu")
		(net 153)
	)
	(segment
		(start 129.55 87.02)
		(end 129.55 88.4992)
		(width 0.2)
		(layer "F.Cu")
		(net 153)
	)
	(segment
		(start 130.675 86.45)
		(end 130.675 85.55)
		(width 0.2)
		(layer "F.Cu")
		(net 157)
	)
	(segment
		(start 131.725 84.5)
		(end 132.875 84.5)
		(width 0.2)
		(layer "F.Cu")
		(net 157)
	)
	(segment
		(start 130.675 85.55)
		(end 131.725 84.5)
		(width 0.2)
		(layer "F.Cu")
		(net 157)
	)
	(segment
		(start 153.025 89.05)
		(end 153.375 88.7)
		(width 0.1)
		(layer "F.Cu")
		(net 158)
	)
	(segment
		(start 152.975 89.05)
		(end 153.025 89.05)
		(width 0.1)
		(layer "F.Cu")
		(net 158)
	)
	(segment
		(start 157.89 87.5)
		(end 157.89 88.55)
		(width 0.1)
		(layer "F.Cu")
		(net 158)
	)
	(segment
		(start 157.89 88.55)
		(end 157.305 88.55)
		(width 0.1)
		(layer "F.Cu")
		(net 158)
	)
	(via
		(at 153.375 88.7)
		(size 0.4)
		(drill 0.15)
		(layers "F.Cu" "B.Cu")
		(net 158)
	)
	(via
		(at 157.305 88.55)
		(size 0.5)
		(drill 0.15)
		(layers "F.Cu" "B.Cu")
		(net 158)
	)
	(segment
		(start 154.305 89.23)
		(end 153.905 89.23)
		(width 0.1)
		(layer "In2.Cu")
		(net 158)
	)
	(segment
		(start 153.905 89.23)
		(end 153.375 88.7)
		(width 0.1)
		(layer "In2.Cu")
		(net 158)
	)
	(segment
		(start 154.985 88.55)
		(end 154.305 89.23)
		(width 0.1)
		(layer "In2.Cu")
		(net 158)
	)
	(segment
		(start 157.305 88.55)
		(end 154.985 88.55)
		(width 0.1)
		(layer "In2.Cu")
		(net 158)
	)
	(segment
		(start 152.975 83.2)
		(end 153.325 83.55)
		(width 0.1)
		(layer "F.Cu")
		(net 159)
	)
	(segment
		(start 157.84 83.55)
		(end 157.89 83.6)
		(width 0.1)
		(layer "F.Cu")
		(net 159)
	)
	(segment
		(start 153.325 83.55)
		(end 157.84 83.55)
		(width 0.1)
		(layer "F.Cu")
		(net 159)
	)
	(segment
		(start 140.725 84.435)
		(end 140.725 85.2)
		(width 0.1)
		(layer "F.Cu")
		(net 160)
	)
	(segment
		(start 145.775 83.2)
		(end 145.584082 83.2)
		(width 0.1)
		(layer "F.Cu")
		(net 160)
	)
	(segment
		(start 140.69 85.235)
		(end 140.725 85.2)
		(width 0.1)
		(layer "F.Cu")
		(net 160)
	)
	(segment
		(start 145.584082 83.2)
		(end 145.284082 82.9)
		(width 0.1)
		(layer "F.Cu")
		(net 160)
	)
	(segment
		(start 140.69 85.9)
		(end 140.69 85.235)
		(width 0.1)
		(layer "F.Cu")
		(net 160)
	)
	(segment
		(start 145.284082 82.9)
		(end 143.989999 82.9)
		(width 0.1)
		(layer "F.Cu")
		(net 160)
	)
	(segment
		(start 143.989999 82.9)
		(end 143.925 82.835001)
		(width 0.1)
		(layer "F.Cu")
		(net 160)
	)
	(via
		(at 143.925 82.835001)
		(size 0.4)
		(drill 0.15)
		(layers "F.Cu" "B.Cu")
		(net 160)
	)
	(via
		(at 140.725 85.2)
		(size 0.4)
		(drill 0.15)
		(layers "F.Cu" "B.Cu")
		(net 160)
	)
	(segment
		(start 143.925 84.55)
		(end 143.275 85.2)
		(width 0.1)
		(layer "B.Cu")
		(net 160)
	)
	(segment
		(start 143.925 82.835001)
		(end 143.925 84.55)
		(width 0.1)
		(layer "B.Cu")
		(net 160)
	)
	(segment
		(start 143.275 85.2)
		(end 140.725 85.2)
		(width 0.1)
		(layer "B.Cu")
		(net 160)
	)
	(segment
		(start 149.931 94.215)
		(end 149.931 94.969)
		(width 0.1)
		(layer "F.Cu")
		(net 161)
	)
	(segment
		(start 150.575 92.95)
		(end 150.575 93.571)
		(width 0.1)
		(layer "F.Cu")
		(net 161)
	)
	(segment
		(start 150.575 93.571)
		(end 149.931 94.215)
		(width 0.1)
		(layer "F.Cu")
		(net 161)
	)
	(segment
		(start 151.325 89.05)
		(end 150.97502 89.39998)
		(width 0.1)
		(layer "F.Cu")
		(net 187)
	)
	(segment
		(start 151.375 89.05)
		(end 151.325 89.05)
		(width 0.1)
		(layer "F.Cu")
		(net 187)
	)
	(segment
		(start 147.425 89.05)
		(end 147.475 89.05)
		(width 0.1)
		(layer "F.Cu")
		(net 187)
	)
	(segment
		(start 147.475 89.05)
		(end 147.775 89.35)
		(width 0.1)
		(layer "F.Cu")
		(net 187)
	)
	(segment
		(start 147.375 89.05)
		(end 147.475 89.05)
		(width 0.1)
		(layer "F.Cu")
		(net 187)
	)
	(segment
		(start 151.24333 83.2)
		(end 150.98628 83.45705)
		(width 0.1)
		(layer "F.Cu")
		(net 187)
	)
	(segment
		(start 151.375 83.2)
		(end 151.24333 83.2)
		(width 0.1)
		(layer "F.Cu")
		(net 187)
	)
	(segment
		(start 147.375 83.2)
		(end 147.475 83.2)
		(width 0.1)
		(layer "F.Cu")
		(net 187)
	)
	(segment
		(start 147.475 83.2)
		(end 147.775 83.5)
		(width 0.1)
		(layer "F.Cu")
		(net 187)
	)
	(segment
		(start 142.925 89.42)
		(end 143.945 89.42)
		(width 0.1)
		(layer "F.Cu")
		(net 187)
	)
	(segment
		(start 132.175 92.1)
		(end 132.175 93.2)
		(width 0.2)
		(layer "F.Cu")
		(net 187)
	)
	(segment
		(start 144.225 89.7)
		(end 144.975 89.7)
		(width 0.1)
		(layer "F.Cu")
		(net 187)
	)
	(segment
		(start 130.725 92.1)
		(end 132.175 92.1)
		(width 0.2)
		(layer "F.Cu")
		(net 187)
	)
	(segment
		(start 154.715 89.7)
		(end 155.085 90.07)
		(width 0.1)
		(layer "F.Cu")
		(net 187)
	)
	(segment
		(start 121.275 83.275)
		(end 122.27501 83.275)
		(width 0.2)
		(layer "F.Cu")
		(net 187)
	)
	(segment
		(start 126.555 89.235)
		(end 126.555 88.515)
		(width 0.2)
		(layer "F.Cu")
		(net 187)
	)
	(segment
		(start 144.425 82.55)
		(end 144.305 82.43)
		(width 0.1)
		(layer "F.Cu")
		(net 187)
	)
	(segment
		(start 132.775 86.45)
		(end 134.16 86.45)
		(width 0.2)
		(layer "F.Cu")
		(net 187)
	)
	(segment
		(start 122.275 81.545)
		(end 122.275 82.62499)
		(width 0.2)
		(layer "F.Cu")
		(net 187)
	)
	(segment
		(start 144.305 82.43)
		(end 142.925 82.43)
		(width 0.1)
		(layer "F.Cu")
		(net 187)
	)
	(segment
		(start 154.97 83.02)
		(end 156.543 83.02)
		(width 0.1)
		(layer "F.Cu")
		(net 187)
	)
	(segment
		(start 130.725 92.1)
		(end 130.725 92.85)
		(width 0.2)
		(layer "F.Cu")
		(net 187)
	)
	(segment
		(start 153.775 82.55)
		(end 154.5 82.55)
		(width 0.1)
		(layer "F.Cu")
		(net 187)
	)
	(segment
		(start 155.085 90.07)
		(end 155.855 90.07)
		(width 0.2)
		(layer "F.Cu")
		(net 187)
	)
	(segment
		(start 126.56 93.07)
		(end 126.56 93.765)
		(width 0.2)
		(layer "F.Cu")
		(net 187)
	)
	(segment
		(start 144.975 82.55)
		(end 144.425 82.55)
		(width 0.1)
		(layer "F.Cu")
		(net 187)
	)
	(segment
		(start 134.595002 89.42)
		(end 134.585 89.409998)
		(width 0.2)
		(layer "F.Cu")
		(net 187)
	)
	(segment
		(start 129.015 81.145)
		(end 129.015 81.825)
		(width 0.2)
		(layer "F.Cu")
		(net 187)
	)
	(segment
		(start 142.275 82.43)
		(end 142.925 82.43)
		(width 0.2)
		(layer "F.Cu")
		(net 187)
	)
	(segment
		(start 134.16 86.45)
		(end 134.175 86.465)
		(width 0.2)
		(layer "F.Cu")
		(net 187)
	)
	(segment
		(start 134.175 85.685)
		(end 134.175 86.465)
		(width 0.2)
		(layer "F.Cu")
		(net 187)
	)
	(segment
		(start 143.945 89.42)
		(end 144.225 89.7)
		(width 0.1)
		(layer "F.Cu")
		(net 187)
	)
	(segment
		(start 154.5 82.55)
		(end 154.97 83.02)
		(width 0.1)
		(layer "F.Cu")
		(net 187)
	)
	(segment
		(start 142.925 89.42)
		(end 134.595002 89.42)
		(width 0.2)
		(layer "F.Cu")
		(net 187)
	)
	(segment
		(start 122.27501 83.925)
		(end 121.275 83.925)
		(width 0.2)
		(layer "F.Cu")
		(net 187)
	)
	(segment
		(start 122.275 82.62499)
		(end 122.27501 82.625)
		(width 0.2)
		(layer "F.Cu")
		(net 187)
	)
	(segment
		(start 153.775 89.7)
		(end 154.715 89.7)
		(width 0.1)
		(layer "F.Cu")
		(net 187)
	)
	(segment
		(start 126.56 93.765)
		(end 126.555 93.77)
		(width 0.2)
		(layer "F.Cu")
		(net 187)
	)
	(via
		(at 150.975 89.39998)
		(size 0.4)
		(drill 0.15)
		(layers "F.Cu" "B.Cu")
		(net 187)
	)
	(via
		(at 147.775 89.35)
		(size 0.4)
		(drill 0.15)
		(layers "F.Cu" "B.Cu")
		(net 187)
	)
	(via
		(at 150.98628 83.45705)
		(size 0.4)
		(drill 0.15)
		(layers "F.Cu" "B.Cu")
		(net 187)
	)
	(via
		(at 147.775 83.5)
		(size 0.4)
		(drill 0.15)
		(layers "F.Cu" "B.Cu")
		(net 187)
	)
	(via
		(at 134.175 86.465)
		(size 0.4)
		(drill 0.15)
		(layers "F.Cu" "B.Cu")
		(net 187)
	)
	(via
		(at 134.585 89.409998)
		(size 0.5)
		(drill 0.15)
		(layers "F.Cu" "B.Cu")
		(net 187)
	)
	(via
		(at 122.275 82.18)
		(size 0.4)
		(drill 0.15)
		(layers "F.Cu" "B.Cu")
		(net 187)
	)
	(via
		(at 155.085 90.07)
		(size 0.4)
		(drill 0.15)
		(layers "F.Cu" "B.Cu")
		(net 187)
	)
	(via
		(at 142.275 82.43)
		(size 0.5)
		(drill 0.15)
		(layers "F.Cu" "B.Cu")
		(net 187)
	)
	(via
		(at 121.275 83.275)
		(size 0.4)
		(drill 0.15)
		(layers "F.Cu" "B.Cu")
		(net 187)
	)
	(via
		(at 129.015 81.825)
		(size 0.4)
		(drill 0.15)
		(layers "F.Cu" "B.Cu")
		(net 187)
	)
	(via
		(at 156.543 83.02)
		(size 0.5)
		(drill 0.15)
		(layers "F.Cu" "B.Cu")
		(net 187)
	)
	(via
		(at 132.175 93.2)
		(size 0.4)
		(drill 0.15)
		(layers "F.Cu" "B.Cu")
		(net 187)
	)
	(via
		(at 130.725 92.85)
		(size 0.4)
		(drill 0.15)
		(layers "F.Cu" "B.Cu")
		(net 187)
	)
	(via
		(at 147.725 86.75)
		(size 0.4)
		(drill 0.15)
		(layers "F.Cu" "B.Cu")
		(net 187)
	)
	(via
		(at 126.555 93.77)
		(size 0.4)
		(drill 0.15)
		(layers "F.Cu" "B.Cu")
		(net 187)
	)
	(via
		(at 121.275 83.925)
		(size 0.4)
		(drill 0.15)
		(layers "F.Cu" "B.Cu")
		(net 187)
	)
	(via
		(at 126.555 88.515)
		(size 0.4)
		(drill 0.15)
		(layers "F.Cu" "B.Cu")
		(net 187)
	)
	(segment
		(start 132.175 96.05)
		(end 131.175 97.05)
		(width 0.2)
		(layer "B.Cu")
		(net 187)
	)
	(segment
		(start 132.175 96.05)
		(end 132.175 95.15)
		(width 0.2)
		(layer "B.Cu")
		(net 187)
	)
	(segment
		(start 131.675 98.7)
		(end 131.675 97.25)
		(width 0.2)
		(layer "B.Cu")
		(net 187)
	)
	(segment
		(start 131.175 97.05)
		(end 131.175 98.7)
		(width 0.2)
		(layer "B.Cu")
		(net 187)
	)
	(segment
		(start 131.675 97.25)
		(end 132.175 96.75)
		(width 0.2)
		(layer "B.Cu")
		(net 187)
	)
	(segment
		(start 132.175 98.7)
		(end 132.175 95.15)
		(width 0.2)
		(layer "B.Cu")
		(net 187)
	)
	(segment
		(start 147.755 86.1)
		(end 147.755 86.72)
		(width 0.1)
		(layer "B.Cu")
		(net 187)
	)
	(segment
		(start 132.175 96.75)
		(end 132.175 96.05)
		(width 0.2)
		(layer "B.Cu")
		(net 187)
	)
	(segment
		(start 141.465 85.88)
		(end 141.735 86.15)
		(width 0.2)
		(layer "In4.Cu")
		(net 187)
	)
	(segment
		(start 155.693 83.87)
		(end 156.543 83.02)
		(width 0.2)
		(layer "In4.Cu")
		(net 187)
	)
	(segment
		(start 141.735 86.15)
		(end 141.795 86.15)
		(width 0.2)
		(layer "In4.Cu")
		(net 187)
	)
	(segment
		(start 150.98628 83.45705)
		(end 150.98628 84.18872)
		(width 0.2)
		(layer "In4.Cu")
		(net 187)
	)
	(segment
		(start 141.465 85.88)
		(end 141.195 86.15)
		(width 0.2)
		(layer "In4.Cu")
		(net 187)
	)
	(segment
		(start 141.465 85.79)
		(end 141.465 85.88)
		(width 0.2)
		(layer "In4.Cu")
		(net 187)
	)
	(segment
		(start 150.125 86.15)
		(end 150.305 86.15)
		(width 0.2)
		(layer "In4.Cu")
		(net 187)
	)
	(segment
		(start 150.075 87.15)
		(end 150.075 86.2)
		(width 0.1)
		(layer "In4.Cu")
		(net 187)
	)
	(segment
		(start 155.693 85.132)
		(end 155.693 83.87)
		(width 0.2)
		(layer "In4.Cu")
		(net 187)
	)
	(segment
		(start 143.925 86.15)
		(end 141.795 86.15)
		(width 0.2)
		(layer "In4.Cu")
		(net 187)
	)
	(segment
		(start 150.325 86.13)
		(end 150.305 86.15)
		(width 0.2)
		(layer "In4.Cu")
		(net 187)
	)
	(segment
		(start 141.465 85.79)
		(end 141.465 86.09)
		(width 0.2)
		(layer "In4.Cu")
		(net 187)
	)
	(segment
		(start 141.795 86.15)
		(end 141.525 86.15)
		(width 0.2)
		(layer "In4.Cu")
		(net 187)
	)
	(segment
		(start 147.735 86.15)
		(end 150.125 86.15)
		(width 0.2)
		(layer "In4.Cu")
		(net 187)
	)
	(segment
		(start 147.725 86.16)
		(end 147.735 86.15)
		(width 0.2)
		(layer "In4.Cu")
		(net 187)
	)
	(segment
		(start 147.375 88.95)
		(end 147.375 87.1)
		(width 0.1)
		(layer "In4.Cu")
		(net 187)
	)
	(segment
		(start 137.844998 86.15)
		(end 134.834999 89.159999)
		(width 0.2)
		(layer "In4.Cu")
		(net 187)
	)
	(segment
		(start 150.98628 84.18872)
		(end 150.325 84.85)
		(width 0.2)
		(layer "In4.Cu")
		(net 187)
	)
	(segment
		(start 141.465 83.24)
		(end 142.275 82.43)
		(width 0.2)
		(layer "In4.Cu")
		(net 187)
	)
	(segment
		(start 155.085 90.07)
		(end 155.485 89.67)
		(width 0.2)
		(layer "In4.Cu")
		(net 187)
	)
	(segment
		(start 141.525 86.15)
		(end 141.195 86.15)
		(width 0.2)
		(layer "In4.Cu")
		(net 187)
	)
	(segment
		(start 141.195 86.15)
		(end 137.844998 86.15)
		(width 0.2)
		(layer "In4.Cu")
		(net 187)
	)
	(segment
		(start 147.775 86.11)
		(end 147.735 86.15)
		(width 0.2)
		(layer "In4.Cu")
		(net 187)
	)
	(segment
		(start 134.834999 89.159999)
		(end 134.585 89.409998)
		(width 0.2)
		(layer "In4.Cu")
		(net 187)
	)
	(segment
		(start 155.485 89.67)
		(end 155.485 86.96)
		(width 0.2)
		(layer "In4.Cu")
		(net 187)
	)
	(segment
		(start 150.325 84.85)
		(end 150.325 86.13)
		(width 0.2)
		(layer "In4.Cu")
		(net 187)
	)
	(segment
		(start 141.465 86.09)
		(end 141.525 86.15)
		(width 0.2)
		(layer "In4.Cu")
		(net 187)
	)
	(segment
		(start 141.465 85.79)
		(end 141.465 83.24)
		(width 0.2)
		(layer "In4.Cu")
		(net 187)
	)
	(segment
		(start 147.735 86.15)
		(end 143.925 86.15)
		(width 0.2)
		(layer "In4.Cu")
		(net 187)
	)
	(segment
		(start 150.975 89.39998)
		(end 150.975 88.05)
		(width 0.1)
		(layer "In4.Cu")
		(net 187)
	)
	(segment
		(start 147.725 86.75)
		(end 147.725 86.16)
		(width 0.2)
		(layer "In4.Cu")
		(net 187)
	)
	(segment
		(start 147.775 83.5)
		(end 147.775 86.11)
		(width 0.2)
		(layer "In4.Cu")
		(net 187)
	)
	(segment
		(start 147.375 87.1)
		(end 147.725 86.75)
		(width 0.1)
		(layer "In4.Cu")
		(net 187)
	)
	(segment
		(start 155.485 86.96)
		(end 154.675 86.15)
		(width 0.2)
		(layer "In4.Cu")
		(net 187)
	)
	(segment
		(start 154.665 86.16)
		(end 155.693 85.132)
		(width 0.2)
		(layer "In4.Cu")
		(net 187)
	)
	(segment
		(start 150.075 86.2)
		(end 150.125 86.15)
		(width 0.1)
		(layer "In4.Cu")
		(net 187)
	)
	(segment
		(start 154.675 86.15)
		(end 150.305 86.15)
		(width 0.2)
		(layer "In4.Cu")
		(net 187)
	)
	(segment
		(start 150.975 88.05)
		(end 150.075 87.15)
		(width 0.1)
		(layer "In4.Cu")
		(net 187)
	)
	(segment
		(start 147.775 89.35)
		(end 147.375 88.95)
		(width 0.1)
		(layer "In4.Cu")
		(net 187)
	)
	(segment
		(start 150.575 89.7)
		(end 150.525 89.7)
		(width 0.1)
		(layer "F.Cu")
		(net 188)
	)
	(segment
		(start 153.875 88.4)
		(end 154.175 88.7)
		(width 0.1)
		(layer "F.Cu")
		(net 188)
	)
	(segment
		(start 153.775 88.4)
		(end 153.875 88.4)
		(width 0.1)
		(layer "F.Cu")
		(net 188)
	)
	(segment
		(start 151.375 79.3)
		(end 151.375 78.8)
		(width 0.1)
		(layer "F.Cu")
		(net 188)
	)
	(segment
		(start 153.64333 85.15)
		(end 153.38628 85.40705)
		(width 0.1)
		(layer "F.Cu")
		(net 188)
	)
	(segment
		(start 153.775 85.15)
		(end 153.64333 85.15)
		(width 0.1)
		(layer "F.Cu")
		(net 188)
	)
	(segment
		(start 153.675 87.1)
		(end 153.375 86.8)
		(width 0.1)
		(layer "F.Cu")
		(net 188)
	)
	(segment
		(start 153.775 87.1)
		(end 153.675 87.1)
		(width 0.1)
		(layer "F.Cu")
		(net 188)
	)
	(segment
		(start 144.84333 85.15)
		(end 144.58628 85.40705)
		(width 0.1)
		(layer "F.Cu")
		(net 188)
	)
	(segment
		(start 144.975 85.15)
		(end 144.84333 85.15)
		(width 0.1)
		(layer "F.Cu")
		(net 188)
	)
	(segment
		(start 150.575 89.7)
		(end 150.475 89.7)
		(width 0.1)
		(layer "F.Cu")
		(net 188)
	)
	(segment
		(start 150.475 89.7)
		(end 150.175 89.4)
		(width 0.1)
		(layer "F.Cu")
		(net 188)
	)
	(segment
		(start 154.175 88.7)
		(end 155.125 88.7)
		(width 0.1)
		(layer "F.Cu")
		(net 188)
	)
	(segment
		(start 150.525 83.85)
		(end 150.17502 84.19998)
		(width 0.1)
		(layer "F.Cu")
		(net 188)
	)
	(segment
		(start 151.375 93.917)
		(end 151.847 94.389)
		(width 0.1)
		(layer "F.Cu")
		(net 188)
	)
	(segment
		(start 152.175 85.15)
		(end 152.04333 85.15)
		(width 0.1)
		(layer "F.Cu")
		(net 188)
	)
	(segment
		(start 154.357 83.85)
		(end 155.087 84.58)
		(width 0.1)
		(layer "F.Cu")
		(net 188)
	)
	(segment
		(start 144.975 83.85)
		(end 144.875 83.85)
		(width 0.1)
		(layer "F.Cu")
		(net 188)
	)
	(segment
		(start 148.175 82.55)
		(end 148.275 82.55)
		(width 0.1)
		(layer "F.Cu")
		(net 188)
	)
	(segment
		(start 149.454 95.718)
		(end 151.511 95.718)
		(width 0.2)
		(layer "F.Cu")
		(net 188)
	)
	(segment
		(start 148.275 83.85)
		(end 148.575 84.15)
		(width 0.1)
		(layer "F.Cu")
		(net 188)
	)
	(segment
		(start 148.225 89.7)
		(end 148.575 89.35)
		(width 0.1)
		(layer "F.Cu")
		(net 188)
	)
	(segment
		(start 149.375 90.15)
		(end 149.375 93.95)
		(width 0.2)
		(layer "F.Cu")
		(net 188)
	)
	(segment
		(start 150.575 88.4)
		(end 150.525 88.4)
		(width 0.1)
		(layer "F.Cu")
		(net 188)
	)
	(segment
		(start 150.475 88.4)
		(end 150.175 88.1)
		(width 0.1)
		(layer "F.Cu")
		(net 188)
	)
	(segment
		(start 152.04333 85.15)
		(end 151.78628 85.40705)
		(width 0.1)
		(layer "F.Cu")
		(net 188)
	)
	(segment
		(start 144.175 88.4)
		(end 143.695 87.92)
		(width 0.1)
		(layer "F.Cu")
		(net 188)
	)
	(segment
		(start 147.375 78.25)
		(end 147.245 78.12)
		(width 0.1)
		(layer "F.Cu")
		(net 188)
	)
	(segment
		(start 150.575 83.85)
		(end 150.525 83.85)
		(width 0.1)
		(layer "F.Cu")
		(net 188)
	)
	(segment
		(start 146.575 85.15)
		(end 146.44333 85.15)
		(width 0.1)
		(layer "F.Cu")
		(net 188)
	)
	(segment
		(start 148.955 95.219)
		(end 149.454 95.718)
		(width 0.2)
		(layer "F.Cu")
		(net 188)
	)
	(segment
		(start 143.345 83.93)
		(end 142.925 83.93)
		(width 0.1)
		(layer "F.Cu")
		(net 188)
	)
	(segment
		(start 143.695 87.92)
		(end 142.925 87.92)
		(width 0.1)
		(layer "F.Cu")
		(net 188)
	)
	(segment
		(start 146.44333 85.15)
		(end 146.18628 85.40705)
		(width 0.1)
		(layer "F.Cu")
		(net 188)
	)
	(segment
		(start 148.175 88.4)
		(end 148.225 88.4)
		(width 0.1)
		(layer "F.Cu")
		(net 188)
	)
	(segment
		(start 144.975 87.1)
		(end 144.875 87.1)
		(width 0.1)
		(layer "F.Cu")
		(net 188)
	)
	(segment
		(start 148.575 89.35)
		(end 149.375 90.15)
		(width 0.2)
		(layer "F.Cu")
		(net 188)
	)
	(segment
		(start 151.455 78.42)
		(end 151.455 77.45)
		(width 0.1)
		(layer "F.Cu")
		(net 188)
	)
	(segment
		(start 151.375 78.8)
		(end 151.375 78.5)
		(width 0.1)
		(layer "F.Cu")
		(net 188)
	)
	(segment
		(start 155.855 84.58)
		(end 155.087 84.58)
		(width 0.2)
		(layer "F.Cu")
		(net 188)
	)
	(segment
		(start 153.775 83.85)
		(end 154.357 83.85)
		(width 0.1)
		(layer "F.Cu")
		(net 188)
	)
	(segment
		(start 152.075 87.1)
		(end 151.775 86.8)
		(width 0.1)
		(layer "F.Cu")
		(net 188)
	)
	(segment
		(start 150.575 82.55)
		(end 150.525 82.55)
		(width 0.1)
		(layer "F.Cu")
		(net 188)
	)
	(segment
		(start 151.375 78.5)
		(end 151.455 78.42)
		(width 0.1)
		(layer "F.Cu")
		(net 188)
	)
	(segment
		(start 147.375 79.3)
		(end 147.375 78.8)
		(width 0.1)
		(layer "F.Cu")
		(net 188)
	)
	(segment
		(start 148.175 83.85)
		(end 148.275 83.85)
		(width 0.1)
		(layer "F.Cu")
		(net 188)
	)
	(segment
		(start 155.125 88.7)
		(end 155.305 88.52)
		(width 0.1)
		(layer "F.Cu")
		(net 188)
	)
	(segment
		(start 148.225 88.4)
		(end 148.575 88.05)
		(width 0.1)
		(layer "F.Cu")
		(net 188)
	)
	(segment
		(start 143.725 83.55)
		(end 143.345 83.93)
		(width 0.1)
		(layer "F.Cu")
		(net 188)
	)
	(segment
		(start 155.305 88.52)
		(end 155.855 88.52)
		(width 0.1)
		(layer "F.Cu")
		(net 188)
	)
	(segment
		(start 147.245 78.12)
		(end 147.245 77.45)
		(width 0.1)
		(layer "F.Cu")
		(net 188)
	)
	(segment
		(start 146.575 87.1)
		(end 146.475 87.1)
		(width 0.1)
		(layer "F.Cu")
		(net 188)
	)
	(segment
		(start 147.571 94.861)
		(end 147.571 93.146)
		(width 0.1)
		(layer "F.Cu")
		(net 188)
	)
	(segment
		(start 144.575 83.55)
		(end 143.725 83.55)
		(width 0.1)
		(layer "F.Cu")
		(net 188)
	)
	(segment
		(start 147.571 93.146)
		(end 147.375 92.95)
		(width 0.1)
		(layer "F.Cu")
		(net 188)
	)
	(segment
		(start 148.175 89.7)
		(end 148.225 89.7)
		(width 0.1)
		(layer "F.Cu")
		(net 188)
	)
	(segment
		(start 151.511 95.718)
		(end 151.847 95.382)
		(width 0.2)
		(layer "F.Cu")
		(net 188)
	)
	(segment
		(start 147.375 78.8)
		(end 147.375 78.25)
		(width 0.1)
		(layer "F.Cu")
		(net 188)
	)
	(segment
		(start 142.925 87.92)
		(end 142.075 87.92)
		(width 0.2)
		(layer "F.Cu")
		(net 188)
	)
	(segment
		(start 152.175 87.1)
		(end 152.075 87.1)
		(width 0.1)
		(layer "F.Cu")
		(net 188)
	)
	(segment
		(start 148.955 94.861)
		(end 147.571 94.861)
		(width 0.2)
		(layer "F.Cu")
		(net 188)
	)
	(segment
		(start 151.847 95.382)
		(end 151.847 94.891)
		(width 0.2)
		(layer "F.Cu")
		(net 188)
	)
	(segment
		(start 149.375 93.95)
		(end 148.955 94.37)
		(width 0.2)
		(layer "F.Cu")
		(net 188)
	)
	(segment
		(start 144.975 88.4)
		(end 144.175 88.4)
		(width 0.1)
		(layer "F.Cu")
		(net 188)
	)
	(segment
		(start 144.875 87.1)
		(end 144.575 86.8)
		(width 0.1)
		(layer "F.Cu")
		(net 188)
	)
	(segment
		(start 148.955 94.872)
		(end 148.955 95.219)
		(width 0.2)
		(layer "F.Cu")
		(net 188)
	)
	(segment
		(start 148.955 94.37)
		(end 148.955 94.872)
		(width 0.2)
		(layer "F.Cu")
		(net 188)
	)
	(segment
		(start 148.955 94.37)
		(end 148.955 94.861)
		(width 0.2)
		(layer "F.Cu")
		(net 188)
	)
	(segment
		(start 150.575 88.4)
		(end 150.475 88.4)
		(width 0.1)
		(layer "F.Cu")
		(net 188)
	)
	(segment
		(start 146.475 87.1)
		(end 146.175 86.8)
		(width 0.1)
		(layer "F.Cu")
		(net 188)
	)
	(segment
		(start 151.375 92.95)
		(end 151.375 93.917)
		(width 0.1)
		(layer "F.Cu")
		(net 188)
	)
	(segment
		(start 148.275 82.55)
		(end 148.575 82.85)
		(width 0.1)
		(layer "F.Cu")
		(net 188)
	)
	(segment
		(start 144.875 83.85)
		(end 144.575 83.55)
		(width 0.1)
		(layer "F.Cu")
		(net 188)
	)
	(segment
		(start 150.525 82.55)
		(end 150.17502 82.89998)
		(width 0.1)
		(layer "F.Cu")
		(net 188)
	)
	(segment
		(start 151.847 94.389)
		(end 151.847 94.891)
		(width 0.1)
		(layer "F.Cu")
		(net 188)
	)
	(via
		(at 154.175 88.7)
		(size 0.4)
		(drill 0.15)
		(layers "F.Cu" "B.Cu")
		(net 188)
	)
	(via
		(at 144.575 83.55)
		(size 0.4)
		(drill 0.15)
		(layers "F.Cu" "B.Cu")
		(net 188)
	)
	(via
		(at 151.375 78.8)
		(size 0.4)
		(drill 0.15)
		(layers "F.Cu" "B.Cu")
		(net 188)
	)
	(via
		(at 153.38628 85.40705)
		(size 0.4)
		(drill 0.15)
		(layers "F.Cu" "B.Cu")
		(net 188)
	)
	(via
		(at 153.375 86.8)
		(size 0.4)
		(drill 0.15)
		(layers "F.Cu" "B.Cu")
		(net 188)
	)
	(via
		(at 144.58628 85.40705)
		(size 0.4)
		(drill 0.15)
		(layers "F.Cu" "B.Cu")
		(net 188)
	)
	(via
		(at 150.175 89.4)
		(size 0.4)
		(drill 0.15)
		(layers "F.Cu" "B.Cu")
		(net 188)
	)
	(via
		(at 146.18628 85.40705)
		(size 0.4)
		(drill 0.15)
		(layers "F.Cu" "B.Cu")
		(net 188)
	)
	(via
		(at 148.575 89.35)
		(size 0.4)
		(drill 0.15)
		(layers "F.Cu" "B.Cu")
		(net 188)
	)
	(via
		(at 126.025 96.35)
		(size 0.5)
		(drill 0.15)
		(layers "F.Cu" "B.Cu")
		(net 188)
	)
	(via
		(at 127.375 95.9)
		(size 0.5)
		(drill 0.15)
		(layers "F.Cu" "B.Cu")
		(net 188)
	)
	(via
		(at 127.725 96.4)
		(size 0.5)
		(drill 0.15)
		(layers "F.Cu" "B.Cu")
		(net 188)
	)
	(via
		(at 150.175 82.89998)
		(size 0.4)
		(drill 0.15)
		(layers "F.Cu" "B.Cu")
		(net 188)
	)
	(via
		(at 148.575 82.85)
		(size 0.4)
		(drill 0.15)
		(layers "F.Cu" "B.Cu")
		(net 188)
	)
	(via
		(at 144.575 86.8)
		(size 0.4)
		(drill 0.15)
		(layers "F.Cu" "B.Cu")
		(net 188)
	)
	(via
		(at 148.575 88.05)
		(size 0.4)
		(drill 0.15)
		(layers "F.Cu" "B.Cu")
		(net 188)
	)
	(via
		(at 147.375 78.8)
		(size 0.4)
		(drill 0.15)
		(layers "F.Cu" "B.Cu")
		(net 188)
	)
	(via
		(at 155.087 84.58)
		(size 0.5)
		(drill 0.15)
		(layers "F.Cu" "B.Cu")
		(net 188)
	)
	(via
		(at 126.925 96.35)
		(size 0.5)
		(drill 0.15)
		(layers "F.Cu" "B.Cu")
		(net 188)
	)
	(via
		(at 125.125 96.35)
		(size 0.5)
		(drill 0.15)
		(layers "F.Cu" "B.Cu")
		(net 188)
	)
	(via
		(at 126.475 95.9)
		(size 0.5)
		(drill 0.15)
		(layers "F.Cu" "B.Cu")
		(net 188)
	)
	(via
		(at 124.675 95.9)
		(size 0.5)
		(drill 0.15)
		(layers "F.Cu" "B.Cu")
		(net 188)
	)
	(via
		(at 142.075 87.92)
		(size 0.4)
		(drill 0.15)
		(layers "F.Cu" "B.Cu")
		(net 188)
	)
	(via
		(at 148.575 84.15)
		(size 0.4)
		(drill 0.15)
		(layers "F.Cu" "B.Cu")
		(net 188)
	)
	(via
		(at 146.175 86.8)
		(size 0.4)
		(drill 0.15)
		(layers "F.Cu" "B.Cu")
		(net 188)
	)
	(via
		(at 151.775 86.8)
		(size 0.4)
		(drill 0.15)
		(layers "F.Cu" "B.Cu")
		(net 188)
	)
	(via
		(at 150.175 88.1)
		(size 0.4)
		(drill 0.15)
		(layers "F.Cu" "B.Cu")
		(net 188)
	)
	(via
		(at 125.575 95.9)
		(size 0.5)
		(drill 0.15)
		(layers "F.Cu" "B.Cu")
		(net 188)
	)
	(via
		(at 150.175 84.19998)
		(size 0.4)
		(drill 0.15)
		(layers "F.Cu" "B.Cu")
		(net 188)
	)
	(via
		(at 151.78628 85.40705)
		(size 0.4)
		(drill 0.15)
		(layers "F.Cu" "B.Cu")
		(net 188)
	)
	(segment
		(start 153.395 86.15)
		(end 153.395 85.41577)
		(width 0.1)
		(layer "B.Cu")
		(net 188)
	)
	(segment
		(start 151.695 86.72)
		(end 151.775 86.8)
		(width 0.1)
		(layer "B.Cu")
		(net 188)
	)
	(segment
		(start 146.18628 86.03128)
		(end 146.255 86.1)
		(width 0.1)
		(layer "B.Cu")
		(net 188)
	)
	(segment
		(start 144.575 86.18)
		(end 144.655 86.1)
		(width 0.1)
		(layer "B.Cu")
		(net 188)
	)
	(segment
		(start 151.695 86.15)
		(end 151.695 85.49833)
		(width 0.1)
		(layer "B.Cu")
		(net 188)
	)
	(segment
		(start 146.18628 85.40705)
		(end 146.18628 86.03128)
		(width 0.1)
		(layer "B.Cu")
		(net 188)
	)
	(segment
		(start 144.58628 85.40705)
		(end 144.58628 86.03128)
		(width 0.1)
		(layer "B.Cu")
		(net 188)
	)
	(segment
		(start 148.755 87.87)
		(end 148.575 88.05)
		(width 0.1)
		(layer "B.Cu")
		(net 188)
	)
	(segment
		(start 146.175 86.18)
		(end 146.255 86.1)
		(width 0.1)
		(layer "B.Cu")
		(net 188)
	)
	(segment
		(start 144.575 86.8)
		(end 144.575 86.18)
		(width 0.1)
		(layer "B.Cu")
		(net 188)
	)
	(segment
		(start 153.395 86.15)
		(end 153.395 86.78)
		(width 0.1)
		(layer "B.Cu")
		(net 188)
	)
	(segment
		(start 151.695 85.49833)
		(end 151.78628 85.40705)
		(width 0.1)
		(layer "B.Cu")
		(net 188)
	)
	(segment
		(start 153.395 86.78)
		(end 153.375 86.8)
		(width 0.1)
		(layer "B.Cu")
		(net 188)
	)
	(segment
		(start 150.105 89.47)
		(end 150.175 89.4)
		(width 0.1)
		(layer "B.Cu")
		(net 188)
	)
	(segment
		(start 148.695 89.47)
		(end 148.575 89.35)
		(width 0.1)
		(layer "B.Cu")
		(net 188)
	)
	(segment
		(start 150.175 84.19998)
		(end 149.60498 84.77)
		(width 0.1)
		(layer "B.Cu")
		(net 188)
	)
	(segment
		(start 148.575 82.85)
		(end 149.025 83.3)
		(width 0.1)
		(layer "B.Cu")
		(net 188)
	)
	(segment
		(start 148.575 84.15)
		(end 149.195 84.77)
		(width 0.1)
		(layer "B.Cu")
		(net 188)
	)
	(segment
		(start 149.775 83.3)
		(end 150.175 82.9)
		(width 0.1)
		(layer "B.Cu")
		(net 188)
	)
	(segment
		(start 151.695 86.15)
		(end 151.695 86.72)
		(width 0.1)
		(layer "B.Cu")
		(net 188)
	)
	(segment
		(start 149.195 84.77)
		(end 149.375 84.77)
		(width 0.1)
		(layer "B.Cu")
		(net 188)
	)
	(segment
		(start 153.395 85.41577)
		(end 153.38628 85.40705)
		(width 0.1)
		(layer "B.Cu")
		(net 188)
	)
	(segment
		(start 149.375 87.87)
		(end 148.755 87.87)
		(width 0.1)
		(layer "B.Cu")
		(net 188)
	)
	(segment
		(start 150.175 82.9)
		(end 150.175 82.89998)
		(width 0.1)
		(layer "B.Cu")
		(net 188)
	)
	(segment
		(start 149.375 87.87)
		(end 149.945 87.87)
		(width 0.1)
		(layer "B.Cu")
		(net 188)
	)
	(segment
		(start 146.175 86.8)
		(end 146.175 86.18)
		(width 0.1)
		(layer "B.Cu")
		(net 188)
	)
	(segment
		(start 149.60498 84.77)
		(end 149.375 84.77)
		(width 0.1)
		(layer "B.Cu")
		(net 188)
	)
	(segment
		(start 149.375 89.47)
		(end 148.695 89.47)
		(width 0.1)
		(layer "B.Cu")
		(net 188)
	)
	(segment
		(start 149.945 87.87)
		(end 150.175 88.1)
		(width 0.1)
		(layer "B.Cu")
		(net 188)
	)
	(segment
		(start 149.375 89.47)
		(end 150.105 89.47)
		(width 0.1)
		(layer "B.Cu")
		(net 188)
	)
	(segment
		(start 149.025 83.3)
		(end 149.775 83.3)
		(width 0.1)
		(layer "B.Cu")
		(net 188)
	)
	(segment
		(start 144.58628 86.03128)
		(end 144.655 86.1)
		(width 0.1)
		(layer "B.Cu")
		(net 188)
	)
	(segment
		(start 150.525 92.3)
		(end 150.17502 92.64998)
		(width 0.1)
		(layer "F.Cu")
		(net 189)
	)
	(segment
		(start 148.175 92.3)
		(end 148.275 92.3)
		(width 0.1)
		(layer "F.Cu")
		(net 189)
	)
	(segment
		(start 148.275 92.3)
		(end 148.575 92.6)
		(width 0.1)
		(layer "F.Cu")
		(net 189)
	)
	(segment
		(start 146.575 92.3)
		(end 146.525 92.3)
		(width 0.1)
		(layer "F.Cu")
		(net 189)
	)
	(segment
		(start 146.525 92.3)
		(end 146.17502 92.64998)
		(width 0.1)
		(layer "F.Cu")
		(net 189)
	)
	(segment
		(start 153.875 91)
		(end 154.175 91.3)
		(width 0.1)
		(layer "F.Cu")
		(net 189)
	)
	(segment
		(start 153.775 91)
		(end 153.875 91)
		(width 0.1)
		(layer "F.Cu")
		(net 189)
	)
	(segment
		(start 146.575 79.95)
		(end 146.675 79.95)
		(width 0.1)
		(layer "F.Cu")
		(net 189)
	)
	(segment
		(start 146.675 79.95)
		(end 146.975 80.25)
		(width 0.1)
		(layer "F.Cu")
		(net 189)
	)
	(segment
		(start 152.275 82.55)
		(end 152.575 82.85)
		(width 0.1)
		(layer "F.Cu")
		(net 189)
	)
	(segment
		(start 152.175 82.55)
		(end 152.275 82.55)
		(width 0.1)
		(layer "F.Cu")
		(net 189)
	)
	(segment
		(start 146.575 82.55)
		(end 146.675 82.55)
		(width 0.1)
		(layer "F.Cu")
		(net 189)
	)
	(segment
		(start 146.675 82.55)
		(end 146.975 82.85)
		(width 0.1)
		(layer "F.Cu")
		(net 189)
	)
	(segment
		(start 158.86 88.55)
		(end 159.625 88.55)
		(width 0.1)
		(layer "F.Cu")
		(net 189)
	)
	(segment
		(start 152.575 92.7)
		(end 152.175 92.3)
		(width 0.1)
		(layer "F.Cu")
		(net 189)
	)
	(segment
		(start 148.275 79.95)
		(end 148.575 80.25)
		(width 0.1)
		(layer "F.Cu")
		(net 189)
	)
	(segment
		(start 150.575 91)
		(end 150.525 91)
		(width 0.1)
		(layer "F.Cu")
		(net 189)
	)
	(segment
		(start 143.355 90.73)
		(end 144.355 90.73)
		(width 0.1)
		(layer "F.Cu")
		(net 189)
	)
	(segment
		(start 150.575 92.3)
		(end 150.525 92.3)
		(width 0.1)
		(layer "F.Cu")
		(net 189)
	)
	(segment
		(start 153.775 81.25)
		(end 154.583 81.25)
		(width 0.1)
		(layer "F.Cu")
		(net 189)
	)
	(segment
		(start 155.855 94.15)
		(end 155.855 93.52)
		(width 0.1)
		(layer "F.Cu")
		(net 189)
	)
	(segment
		(start 152.945 93.52)
		(end 152.575 93.15)
		(width 0.1)
		(layer "F.Cu")
		(net 189)
	)
	(segment
		(start 140.725 83.465)
		(end 140.725 82.75)
		(width 0.1)
		(layer "F.Cu")
		(net 189)
	)
	(segment
		(start 148.175 79.95)
		(end 148.275 79.95)
		(width 0.1)
		(layer "F.Cu")
		(net 189)
	)
	(segment
		(start 142.925 80.93)
		(end 143.825 80.93)
		(width 0.1)
		(layer "F.Cu")
		(net 189)
	)
	(segment
		(start 150.525 79.95)
		(end 150.17502 80.29998)
		(width 0.1)
		(layer "F.Cu")
		(net 189)
	)
	(segment
		(start 144.145 81.25)
		(end 143.825 80.93)
		(width 0.1)
		(layer "F.Cu")
		(net 189)
	)
	(segment
		(start 146.575 89.7)
		(end 146.625 89.7)
		(width 0.1)
		(layer "F.Cu")
		(net 189)
	)
	(segment
		(start 152.175 79.95)
		(end 152.275 79.95)
		(width 0.1)
		(layer "F.Cu")
		(net 189)
	)
	(segment
		(start 144.355 90.73)
		(end 144.625 91)
		(width 0.1)
		(layer "F.Cu")
		(net 189)
	)
	(segment
		(start 154.175 91.3)
		(end 155.775 91.3)
		(width 0.1)
		(layer "F.Cu")
		(net 189)
	)
	(segment
		(start 148.175 81.25)
		(end 148.275 81.25)
		(width 0.1)
		(layer "F.Cu")
		(net 189)
	)
	(segment
		(start 152.125 89.7)
		(end 151.775 90.05)
		(width 0.1)
		(layer "F.Cu")
		(net 189)
	)
	(segment
		(start 146.625 89.7)
		(end 146.997488 90.072488)
		(width 0.1)
		(layer "F.Cu")
		(net 189)
	)
	(segment
		(start 154.583 81.25)
		(end 154.853 81.52)
		(width 0.1)
		(layer "F.Cu")
		(net 189)
	)
	(segment
		(start 155.775 91.3)
		(end 155.855 91.38)
		(width 0.1)
		(layer "F.Cu")
		(net 189)
	)
	(segment
		(start 158.86 82.8)
		(end 158.86 83.6)
		(width 0.1)
		(layer "F.Cu")
		(net 189)
	)
	(segment
		(start 144.625 91)
		(end 144.975 91)
		(width 0.1)
		(layer "F.Cu")
		(net 189)
	)
	(segment
		(start 150.575 81.25)
		(end 150.525 81.25)
		(width 0.1)
		(layer "F.Cu")
		(net 189)
	)
	(segment
		(start 152.175 89.7)
		(end 152.125 89.7)
		(width 0.1)
		(layer "F.Cu")
		(net 189)
	)
	(segment
		(start 152.575 93.15)
		(end 152.575 92.7)
		(width 0.1)
		(layer "F.Cu")
		(net 189)
	)
	(segment
		(start 150.575 79.95)
		(end 150.525 79.95)
		(width 0.1)
		(layer "F.Cu")
		(net 189)
	)
	(segment
		(start 148.275 91)
		(end 148.575 91.3)
		(width 0.1)
		(layer "F.Cu")
		(net 189)
	)
	(segment
		(start 143.355 90.73)
		(end 143.255 90.73)
		(width 0.1)
		(layer "F.Cu")
		(net 189)
	)
	(segment
		(start 144.975 81.25)
		(end 144.145 81.25)
		(width 0.1)
		(layer "F.Cu")
		(net 189)
	)
	(segment
		(start 142.625 90.73)
		(end 143.355 90.73)
		(width 0.2)
		(layer "F.Cu")
		(net 189)
	)
	(segment
		(start 156.543 81.52)
		(end 154.853 81.52)
		(width 0.1)
		(layer "F.Cu")
		(net 189)
	)
	(segment
		(start 150.525 81.25)
		(end 150.17502 81.59998)
		(width 0.1)
		(layer "F.Cu")
		(net 189)
	)
	(segment
		(start 155.855 93.52)
		(end 152.945 93.52)
		(width 0.1)
		(layer "F.Cu")
		(net 189)
	)
	(segment
		(start 152.275 79.95)
		(end 152.575 80.25)
		(width 0.1)
		(layer "F.Cu")
		(net 189)
	)
	(segment
		(start 148.275 81.25)
		(end 148.575 81.55)
		(width 0.1)
		(layer "F.Cu")
		(net 189)
	)
	(segment
		(start 150.525 91)
		(end 150.17502 91.34998)
		(width 0.1)
		(layer "F.Cu")
		(net 189)
	)
	(segment
		(start 148.175 91)
		(end 148.275 91)
		(width 0.1)
		(layer "F.Cu")
		(net 189)
	)
	(via
		(at 150.175 92.64998)
		(size 0.4)
		(drill 0.15)
		(layers "F.Cu" "B.Cu")
		(net 189)
	)
	(via
		(at 148.575 92.6)
		(size 0.4)
		(drill 0.15)
		(layers "F.Cu" "B.Cu")
		(net 189)
	)
	(via
		(at 146.175 92.64998)
		(size 0.4)
		(drill 0.15)
		(layers "F.Cu" "B.Cu")
		(net 189)
	)
	(via
		(at 154.175 91.3)
		(size 0.4)
		(drill 0.15)
		(layers "F.Cu" "B.Cu")
		(net 189)
	)
	(via
		(at 146.975 80.25)
		(size 0.4)
		(drill 0.15)
		(layers "F.Cu" "B.Cu")
		(net 189)
	)
	(via
		(at 152.575 82.85)
		(size 0.4)
		(drill 0.15)
		(layers "F.Cu" "B.Cu")
		(net 189)
	)
	(via
		(at 146.975 82.85)
		(size 0.4)
		(drill 0.15)
		(layers "F.Cu" "B.Cu")
		(net 189)
	)
	(via
		(at 148.575 91.3)
		(size 0.4)
		(drill 0.15)
		(layers "F.Cu" "B.Cu")
		(net 189)
	)
	(via
		(at 159.625 88.55)
		(size 0.5)
		(drill 0.15)
		(layers "F.Cu" "B.Cu")
		(net 189)
	)
	(via
		(at 148.575 81.55)
		(size 0.4)
		(drill 0.15)
		(layers "F.Cu" "B.Cu")
		(net 189)
	)
	(via
		(at 165.225 95.7)
		(size 0.5)
		(drill 0.15)
		(layers "F.Cu" "B.Cu")
		(net 189)
	)
	(via
		(at 140.725 82.75)
		(size 0.5)
		(drill 0.15)
		(layers "F.Cu" "B.Cu")
		(net 189)
	)
	(via
		(at 143.825 80.93)
		(size 0.4)
		(drill 0.15)
		(layers "F.Cu" "B.Cu")
		(net 189)
	)
	(via
		(at 134.775 96.25)
		(size 0.5)
		(drill 0.15)
		(layers "F.Cu" "B.Cu")
		(net 189)
	)
	(via
		(at 150.175 80.29998)
		(size 0.4)
		(drill 0.15)
		(layers "F.Cu" "B.Cu")
		(net 189)
	)
	(via
		(at 164.925 96.25)
		(size 0.5)
		(drill 0.15)
		(layers "F.Cu" "B.Cu")
		(net 189)
	)
	(via
		(at 164.675 95.7)
		(size 0.5)
		(drill 0.15)
		(layers "F.Cu" "B.Cu")
		(net 189)
	)
	(via
		(at 148.575 80.25)
		(size 0.4)
		(drill 0.15)
		(layers "F.Cu" "B.Cu")
		(net 189)
	)
	(via
		(at 143.255 90.73)
		(size 0.4)
		(drill 0.15)
		(layers "F.Cu" "B.Cu")
		(net 189)
	)
	(via
		(at 158.86 82.8)
		(size 0.5)
		(drill 0.15)
		(layers "F.Cu" "B.Cu")
		(net 189)
	)
	(via
		(at 133.675 95.8)
		(size 0.5)
		(drill 0.15)
		(layers "F.Cu" "B.Cu")
		(net 189)
	)
	(via
		(at 164.375 96.25)
		(size 0.5)
		(drill 0.15)
		(layers "F.Cu" "B.Cu")
		(net 189)
	)
	(via
		(at 156.543 81.52)
		(size 0.5)
		(drill 0.15)
		(layers "F.Cu" "B.Cu")
		(net 189)
	)
	(via
		(at 134.425 95.8)
		(size 0.5)
		(drill 0.15)
		(layers "F.Cu" "B.Cu")
		(net 189)
	)
	(via
		(at 163.825 96.25)
		(size 0.5)
		(drill 0.15)
		(layers "F.Cu" "B.Cu")
		(net 189)
	)
	(via
		(at 132.875 95.8)
		(size 0.5)
		(drill 0.15)
		(layers "F.Cu" "B.Cu")
		(net 189)
	)
	(via
		(at 163.575 95.7)
		(size 0.5)
		(drill 0.15)
		(layers "F.Cu" "B.Cu")
		(net 189)
	)
	(via
		(at 152.575 80.25)
		(size 0.4)
		(drill 0.15)
		(layers "F.Cu" "B.Cu")
		(net 189)
	)
	(via
		(at 155.855 94.15)
		(size 0.5)
		(drill 0.15)
		(layers "F.Cu" "B.Cu")
		(net 189)
	)
	(via
		(at 150.175 91.34998)
		(size 0.4)
		(drill 0.15)
		(layers "F.Cu" "B.Cu")
		(net 189)
	)
	(via
		(at 146.997488 90.072488)
		(size 0.4)
		(drill 0.15)
		(layers "F.Cu" "B.Cu")
		(net 189)
	)
	(via
		(at 134.025 96.25)
		(size 0.5)
		(drill 0.15)
		(layers "F.Cu" "B.Cu")
		(net 189)
	)
	(via
		(at 151.775 90.05)
		(size 0.4)
		(drill 0.15)
		(layers "F.Cu" "B.Cu")
		(net 189)
	)
	(via
		(at 133.275 96.25)
		(size 0.5)
		(drill 0.15)
		(layers "F.Cu" "B.Cu")
		(net 189)
	)
	(via
		(at 150.175 81.59998)
		(size 0.4)
		(drill 0.15)
		(layers "F.Cu" "B.Cu")
		(net 189)
	)
	(via
		(at 164.125 95.7)
		(size 0.5)
		(drill 0.15)
		(layers "F.Cu" "B.Cu")
		(net 189)
	)
	(segment
		(start 150.00498 81.77)
		(end 150.175 81.59998)
		(width 0.1)
		(layer "B.Cu")
		(net 189)
	)
	(segment
		(start 153.325 82.88)
		(end 152.605 82.88)
		(width 0.1)
		(layer "B.Cu")
		(net 189)
	)
	(segment
		(start 148.575 80.25)
		(end 149.355 80.25)
		(width 0.1)
		(layer "B.Cu")
		(net 189)
	)
	(segment
		(start 146.975 80.98)
		(end 146.975 80.25)
		(width 0.1)
		(layer "B.Cu")
		(net 189)
	)
	(segment
		(start 149.355 80.25)
		(end 149.375 80.27)
		(width 0.1)
		(layer "B.Cu")
		(net 189)
	)
	(segment
		(start 148.795 81.77)
		(end 148.575 81.55)
		(width 0.1)
		(layer "B.Cu")
		(net 189)
	)
	(segment
		(start 149.54502 92.64998)
		(end 149.375 92.82)
		(width 0.1)
		(layer "B.Cu")
		(net 189)
	)
	(segment
		(start 149.375 81.77)
		(end 150.00498 81.77)
		(width 0.1)
		(layer "B.Cu")
		(net 189)
	)
	(segment
		(start 146.905 82.78)
		(end 146.975 82.85)
		(width 0.1)
		(layer "B.Cu")
		(net 189)
	)
	(segment
		(start 146.175 92.64998)
		(end 146.48302 92.64998)
		(width 0.1)
		(layer "B.Cu")
		(net 189)
	)
	(segment
		(start 146.48302 92.64998)
		(end 146.803 92.33)
		(width 0.1)
		(layer "B.Cu")
		(net 189)
	)
	(segment
		(start 150.175 91.34998)
		(end 149.40498 91.34998)
		(width 0.1)
		(layer "B.Cu")
		(net 189)
	)
	(segment
		(start 148.575 91.3)
		(end 149.355 91.3)
		(width 0.1)
		(layer "B.Cu")
		(net 189)
	)
	(segment
		(start 149.40498 91.34998)
		(end 149.375 91.32)
		(width 0.1)
		(layer "B.Cu")
		(net 189)
	)
	(segment
		(start 149.355 91.3)
		(end 149.375 91.32)
		(width 0.1)
		(layer "B.Cu")
		(net 189)
	)
	(segment
		(start 152.575 81.08)
		(end 152.575 80.25)
		(width 0.1)
		(layer "B.Cu")
		(net 189)
	)
	(segment
		(start 146.275 82.78)
		(end 146.905 82.78)
		(width 0.1)
		(layer "B.Cu")
		(net 189)
	)
	(segment
		(start 152.605 82.88)
		(end 152.575 82.85)
		(width 0.1)
		(layer "B.Cu")
		(net 189)
	)
	(segment
		(start 149.155 92.6)
		(end 149.375 92.82)
		(width 0.1)
		(layer "B.Cu")
		(net 189)
	)
	(segment
		(start 150.14502 80.27)
		(end 150.175 80.29998)
		(width 0.1)
		(layer "B.Cu")
		(net 189)
	)
	(segment
		(start 148.575 92.6)
		(end 149.155 92.6)
		(width 0.1)
		(layer "B.Cu")
		(net 189)
	)
	(segment
		(start 149.375 80.27)
		(end 150.14502 80.27)
		(width 0.1)
		(layer "B.Cu")
		(net 189)
	)
	(segment
		(start 149.375 81.77)
		(end 148.795 81.77)
		(width 0.1)
		(layer "B.Cu")
		(net 189)
	)
	(segment
		(start 150.175 92.64998)
		(end 149.54502 92.64998)
		(width 0.1)
		(layer "B.Cu")
		(net 189)
	)
	(segment
		(start 152.975 92.3)
		(end 153.075 92.3)
		(width 0.1)
		(layer "F.Cu")
		(net 190)
	)
	(segment
		(start 153.075 92.3)
		(end 153.375 92.6)
		(width 0.1)
		(layer "F.Cu")
		(net 190)
	)
	(segment
		(start 153.925 98.7)
		(end 153.925 96.825)
		(width 0.2)
		(layer "F.Cu")
		(net 190)
	)
	(via
		(at 153.375 92.6)
		(size 0.4)
		(drill 0.15)
		(layers "F.Cu" "B.Cu")
		(net 190)
	)
	(via
		(at 153.925 96.825)
		(size 0.4)
		(drill 0.15)
		(layers "F.Cu" "B.Cu")
		(net 190)
	)
	(segment
		(start 153.375 92.882842)
		(end 153.375 92.6)
		(width 0.1)
		(layer "In2.Cu")
		(net 190)
	)
	(segment
		(start 153.629528 95.301998)
		(end 153.629528 95.001998)
		(width 0.1)
		(layer "In2.Cu")
		(net 190)
	)
	(segment
		(start 153.629528 93.401998)
		(end 153.629528 93.13737)
		(width 0.1)
		(layer "In2.Cu")
		(net 190)
	)
	(segment
		(start 153.825 96)
		(end 154.075 96)
		(width 0.1)
		(layer "In2.Cu")
		(net 190)
	)
	(segment
		(start 153.529528 93.901998)
		(end 153.854865 93.901998)
		(width 0.1)
		(layer "In2.Cu")
		(net 190)
	)
	(segment
		(start 153.836849 95.261355)
		(end 153.783577 95.314626)
		(width 0.1)
		(layer "In2.Cu")
		(net 190)
	)
	(segment
		(start 153.924999 95.456049)
		(end 153.925 95.456048)
		(width 0.1)
		(layer "In2.Cu")
		(net 190)
	)
	(segment
		(start 153.925 96.825)
		(end 153.925 96.3)
		(width 0.1)
		(layer "In2.Cu")
		(net 190)
	)
	(segment
		(start 153.629528 93.13737)
		(end 153.375 92.882842)
		(width 0.1)
		(layer "In2.Cu")
		(net 190)
	)
	(segment
		(start 153.642156 95.314625)
		(end 153.642156 95.314626)
		(width 0.1)
		(layer "In2.Cu")
		(net 190)
	)
	(segment
		(start 153.629528 93.701998)
		(end 153.454191 93.701998)
		(width 0.1)
		(layer "In2.Cu")
		(net 190)
	)
	(segment
		(start 153.729528 94.901998)
		(end 153.854865 94.901998)
		(width 0.1)
		(layer "In2.Cu")
		(net 190)
	)
	(segment
		(start 153.529528 94.101998)
		(end 153.454191 94.101998)
		(width 0.1)
		(layer "In2.Cu")
		(net 190)
	)
	(segment
		(start 153.729528 94.501998)
		(end 153.854865 94.501998)
		(width 0.1)
		(layer "In2.Cu")
		(net 190)
	)
	(segment
		(start 153.925 95.456048)
		(end 153.978271 95.402776)
		(width 0.1)
		(layer "In2.Cu")
		(net 190)
	)
	(segment
		(start 153.854865 93.701998)
		(end 153.629528 93.701998)
		(width 0.1)
		(layer "In2.Cu")
		(net 190)
	)
	(segment
		(start 153.854865 94.301998)
		(end 153.729528 94.301998)
		(width 0.1)
		(layer "In2.Cu")
		(net 190)
	)
	(segment
		(start 153.454191 93.901998)
		(end 153.529528 93.901998)
		(width 0.1)
		(layer "In2.Cu")
		(net 190)
	)
	(segment
		(start 154.075 95.8)
		(end 154.025 95.8)
		(width 0.1)
		(layer "In2.Cu")
		(net 190)
	)
	(segment
		(start 153.925 95.7)
		(end 153.925 95.59747)
		(width 0.1)
		(layer "In2.Cu")
		(net 190)
	)
	(segment
		(start 153.854865 94.701998)
		(end 153.729528 94.701998)
		(width 0.1)
		(layer "In2.Cu")
		(net 190)
	)
	(segment
		(start 153.454191 93.501998)
		(end 153.529528 93.501998)
		(width 0.1)
		(layer "In2.Cu")
		(net 190)
	)
	(segment
		(start 153.83685 95.261354)
		(end 153.836849 95.261355)
		(width 0.1)
		(layer "In2.Cu")
		(net 190)
	)
	(segment
		(start 153.642156 95.314626)
		(end 153.629528 95.301998)
		(width 0.1)
		(layer "In2.Cu")
		(net 190)
	)
	(segment
		(start 153.97827 95.261355)
		(end 153.978271 95.261355)
		(width 0.1)
		(layer "In2.Cu")
		(net 190)
	)
	(arc
		(start 153.629528 95.001998)
		(mid 153.658817 94.931287)
		(end 153.729528 94.901998)
		(width 0.1)
		(layer "In2.Cu")
		(net 190)
	)
	(arc
		(start 153.454191 94.101998)
		(mid 153.38348 94.072709)
		(end 153.354191 94.001998)
		(width 0.1)
		(layer "In2.Cu")
		(net 190)
	)
	(arc
		(start 153.629528 94.601998)
		(mid 153.658817 94.531287)
		(end 153.729528 94.501998)
		(width 0.1)
		(layer "In2.Cu")
		(net 190)
	)
	(arc
		(start 153.854865 94.501998)
		(mid 153.925576 94.472709)
		(end 153.954865 94.401998)
		(width 0.1)
		(layer "In2.Cu")
		(net 190)
	)
	(arc
		(start 153.729528 94.301998)
		(mid 153.658817 94.272709)
		(end 153.629528 94.201998)
		(width 0.1)
		(layer "In2.Cu")
		(net 190)
	)
	(arc
		(start 153.854865 93.901998)
		(mid 153.925576 93.872709)
		(end 153.954865 93.801998)
		(width 0.1)
		(layer "In2.Cu")
		(net 190)
	)
	(arc
		(start 153.954865 94.801998)
		(mid 153.925576 94.731287)
		(end 153.854865 94.701998)
		(width 0.1)
		(layer "In2.Cu")
		(net 190)
	)
	(arc
		(start 153.529528 93.501998)
		(mid 153.600239 93.472709)
		(end 153.629528 93.401998)
		(width 0.1)
		(layer "In2.Cu")
		(net 190)
	)
	(arc
		(start 153.825 96.2)
		(mid 153.754289 96.170711)
		(end 153.725 96.1)
		(width 0.1)
		(layer "In2.Cu")
		(net 190)
	)
	(arc
		(start 153.925 95.59747)
		(mid 153.89571 95.52676)
		(end 153.924999 95.456049)
		(width 0.1)
		(layer "In2.Cu")
		(net 190)
	)
	(arc
		(start 153.954865 93.801998)
		(mid 153.925576 93.731287)
		(end 153.854865 93.701998)
		(width 0.1)
		(layer "In2.Cu")
		(net 190)
	)
	(arc
		(start 154.025 95.8)
		(mid 153.954289 95.770711)
		(end 153.925 95.7)
		(width 0.1)
		(layer "In2.Cu")
		(net 190)
	)
	(arc
		(start 153.925 96.3)
		(mid 153.895711 96.229289)
		(end 153.825 96.2)
		(width 0.1)
		(layer "In2.Cu")
		(net 190)
	)
	(arc
		(start 153.354191 94.001998)
		(mid 153.38348 93.931287)
		(end 153.454191 93.901998)
		(width 0.1)
		(layer "In2.Cu")
		(net 190)
	)
	(arc
		(start 153.978271 95.402776)
		(mid 154.00756 95.332065)
		(end 153.97827 95.261355)
		(width 0.1)
		(layer "In2.Cu")
		(net 190)
	)
	(arc
		(start 154.075 96)
		(mid 154.145711 95.970711)
		(end 154.175 95.9)
		(width 0.1)
		(layer "In2.Cu")
		(net 190)
	)
	(arc
		(start 153.854865 94.901998)
		(mid 153.925576 94.872709)
		(end 153.954865 94.801998)
		(width 0.1)
		(layer "In2.Cu")
		(net 190)
	)
	(arc
		(start 153.354191 93.601998)
		(mid 153.38348 93.531287)
		(end 153.454191 93.501998)
		(width 0.1)
		(layer "In2.Cu")
		(net 190)
	)
	(arc
		(start 153.629528 94.201998)
		(mid 153.600239 94.131287)
		(end 153.529528 94.101998)
		(width 0.1)
		(layer "In2.Cu")
		(net 190)
	)
	(arc
		(start 153.729528 94.701998)
		(mid 153.658817 94.672709)
		(end 153.629528 94.601998)
		(width 0.1)
		(layer "In2.Cu")
		(net 190)
	)
	(arc
		(start 153.454191 93.701998)
		(mid 153.38348 93.672709)
		(end 153.354191 93.601998)
		(width 0.1)
		(layer "In2.Cu")
		(net 190)
	)
	(arc
		(start 153.978271 95.261355)
		(mid 153.907561 95.232065)
		(end 153.83685 95.261354)
		(width 0.1)
		(layer "In2.Cu")
		(net 190)
	)
	(arc
		(start 153.783577 95.314626)
		(mid 153.712866 95.343915)
		(end 153.642156 95.314625)
		(width 0.1)
		(layer "In2.Cu")
		(net 190)
	)
	(arc
		(start 153.725 96.1)
		(mid 153.754289 96.029289)
		(end 153.825 96)
		(width 0.1)
		(layer "In2.Cu")
		(net 190)
	)
	(arc
		(start 153.954865 94.401998)
		(mid 153.925576 94.331287)
		(end 153.854865 94.301998)
		(width 0.1)
		(layer "In2.Cu")
		(net 190)
	)
	(arc
		(start 154.175 95.9)
		(mid 154.145711 95.829289)
		(end 154.075 95.8)
		(width 0.1)
		(layer "In2.Cu")
		(net 190)
	)
	(segment
		(start 154.425 98.7)
		(end 154.425 96.325)
		(width 0.2)
		(layer "F.Cu")
		(net 191)
	)
	(segment
		(start 153.075 91.65)
		(end 153.375 91.95)
		(width 0.1)
		(layer "F.Cu")
		(net 191)
	)
	(segment
		(start 152.975 91.65)
		(end 153.075 91.65)
		(width 0.1)
		(layer "F.Cu")
		(net 191)
	)
	(via
		(at 154.425 96.325)
		(size 0.4)
		(drill 0.15)
		(layers "F.Cu" "B.Cu")
		(net 191)
	)
	(via
		(at 153.375 91.95)
		(size 0.4)
		(drill 0.15)
		(layers "F.Cu" "B.Cu")
		(net 191)
	)
	(segment
		(start 154.008578 92.375)
		(end 153.999074 92.384501)
		(width 0.1)
		(layer "In2.Cu")
		(net 191)
	)
	(segment
		(start 153.725 91.95)
		(end 153.375 91.95)
		(width 0.1)
		(layer "In2.Cu")
		(net 191)
	)
	(segment
		(start 154.125 93.3)
		(end 154.375 93.3)
		(width 0.1)
		(layer "In2.Cu")
		(net 191)
	)
	(segment
		(start 154.225 92.9)
		(end 154.375 92.9)
		(width 0.1)
		(layer "In2.Cu")
		(net 191)
	)
	(segment
		(start 154.425 96.325)
		(end 154.425 95.8)
		(width 0.1)
		(layer "In2.Cu")
		(net 191)
	)
	(segment
		(start 154.225 92.6)
		(end 154.225 92.45)
		(width 0.1)
		(layer "In2.Cu")
		(net 191)
	)
	(segment
		(start 154.375 92.7)
		(end 154.325 92.7)
		(width 0.1)
		(layer "In2.Cu")
		(net 191)
	)
	(segment
		(start 153.857653 92.384502)
		(end 153.857652 92.384501)
		(width 0.1)
		(layer "In2.Cu")
		(net 191)
	)
	(segment
		(start 154.225 92.45)
		(end 154.15 92.375)
		(width 0.1)
		(layer "In2.Cu")
		(net 191)
	)
	(segment
		(start 153.867155 92.092155)
		(end 153.725 91.95)
		(width 0.1)
		(layer "In2.Cu")
		(net 191)
	)
	(segment
		(start 154.375 93.1)
		(end 154.225 93.1)
		(width 0.1)
		(layer "In2.Cu")
		(net 191)
	)
	(segment
		(start 153.975 93.3)
		(end 154.125 93.3)
		(width 0.1)
		(layer "In2.Cu")
		(net 191)
	)
	(segment
		(start 153.857652 92.243079)
		(end 153.867155 92.233577)
		(width 0.1)
		(layer "In2.Cu")
		(net 191)
	)
	(segment
		(start 154.425 95.8)
		(end 154.225 95.6)
		(width 0.1)
		(layer "In2.Cu")
		(net 191)
	)
	(segment
		(start 154.225 95.6)
		(end 154.225 93.6)
		(width 0.1)
		(layer "In2.Cu")
		(net 191)
	)
	(segment
		(start 154.125 93.5)
		(end 153.975 93.5)
		(width 0.1)
		(layer "In2.Cu")
		(net 191)
	)
	(segment
		(start 153.857651 92.24308)
		(end 153.857652 92.243079)
		(width 0.1)
		(layer "In2.Cu")
		(net 191)
	)
	(segment
		(start 154.225 93.1)
		(end 153.925 93.1)
		(width 0.1)
		(layer "In2.Cu")
		(net 191)
	)
	(segment
		(start 153.867156 92.092156)
		(end 153.867155 92.092155)
		(width 0.1)
		(layer "In2.Cu")
		(net 191)
	)
	(segment
		(start 154.008579 92.374999)
		(end 154.008578 92.375)
		(width 0.1)
		(layer "In2.Cu")
		(net 191)
	)
	(segment
		(start 153.925 92.9)
		(end 154.225 92.9)
		(width 0.1)
		(layer "In2.Cu")
		(net 191)
	)
	(arc
		(start 154.225 93.6)
		(mid 154.195711 93.529289)
		(end 154.125 93.5)
		(width 0.1)
		(layer "In2.Cu")
		(net 191)
	)
	(arc
		(start 153.975 93.5)
		(mid 153.904289 93.470711)
		(end 153.875 93.4)
		(width 0.1)
		(layer "In2.Cu")
		(net 191)
	)
	(arc
		(start 153.825 93)
		(mid 153.854289 92.929289)
		(end 153.925 92.9)
		(width 0.1)
		(layer "In2.Cu")
		(net 191)
	)
	(arc
		(start 154.475 93.2)
		(mid 154.445711 93.129289)
		(end 154.375 93.1)
		(width 0.1)
		(layer "In2.Cu")
		(net 191)
	)
	(arc
		(start 153.867155 92.233577)
		(mid 153.896445 92.162867)
		(end 153.867156 92.092156)
		(width 0.1)
		(layer "In2.Cu")
		(net 191)
	)
	(arc
		(start 153.925 93.1)
		(mid 153.854289 93.070711)
		(end 153.825 93)
		(width 0.1)
		(layer "In2.Cu")
		(net 191)
	)
	(arc
		(start 154.325 92.7)
		(mid 154.254289 92.670711)
		(end 154.225 92.6)
		(width 0.1)
		(layer "In2.Cu")
		(net 191)
	)
	(arc
		(start 154.375 92.9)
		(mid 154.445711 92.870711)
		(end 154.475 92.8)
		(width 0.1)
		(layer "In2.Cu")
		(net 191)
	)
	(arc
		(start 154.475 92.8)
		(mid 154.445711 92.729289)
		(end 154.375 92.7)
		(width 0.1)
		(layer "In2.Cu")
		(net 191)
	)
	(arc
		(start 153.875 93.4)
		(mid 153.904289 93.329289)
		(end 153.975 93.3)
		(width 0.1)
		(layer "In2.Cu")
		(net 191)
	)
	(arc
		(start 153.857652 92.384501)
		(mid 153.828362 92.313791)
		(end 153.857651 92.24308)
		(width 0.1)
		(layer "In2.Cu")
		(net 191)
	)
	(arc
		(start 154.15 92.375)
		(mid 154.07929 92.34571)
		(end 154.008579 92.374999)
		(width 0.1)
		(layer "In2.Cu")
		(net 191)
	)
	(arc
		(start 153.999074 92.384501)
		(mid 153.928364 92.413791)
		(end 153.857653 92.384502)
		(width 0.1)
		(layer "In2.Cu")
		(net 191)
	)
	(arc
		(start 154.375 93.3)
		(mid 154.445711 93.270711)
		(end 154.475 93.2)
		(width 0.1)
		(layer "In2.Cu")
		(net 191)
	)
	(segment
		(start 152.975 88.4)
		(end 152.925 88.4)
		(width 0.1)
		(layer "F.Cu")
		(net 192)
	)
	(segment
		(start 152.925 88.4)
		(end 152.57502 88.74998)
		(width 0.1)
		(layer "F.Cu")
		(net 192)
	)
	(via
		(at 152.575 88.74998)
		(size 0.4)
		(drill 0.15)
		(layers "F.Cu" "B.Cu")
		(net 192)
	)
	(segment
		(start 154.025 96.430025)
		(end 154.025 96.15)
		(width 0.1)
		(layer "B.Cu")
		(net 192)
	)
	(segment
		(start 154.145 96.03)
		(end 154.145 94.545)
		(width 0.1)
		(layer "B.Cu")
		(net 192)
	)
	(segment
		(start 154.275 96.680025)
		(end 154.025 96.430025)
		(width 0.1)
		(layer "B.Cu")
		(net 192)
	)
	(segment
		(start 154.175 98.7)
		(end 154.175 97.125)
		(width 0.1)
		(layer "B.Cu")
		(net 192)
	)
	(segment
		(start 154.145 92.952552)
		(end 154.145 92.902552)
		(width 0.1)
		(layer "B.Cu")
		(net 192)
	)
	(segment
		(start 153.57 93.627552)
		(end 154.02 93.627552)
		(width 0.1)
		(layer "B.Cu")
		(net 192)
	)
	(segment
		(start 154.175 97.125)
		(end 154.275 97.025)
		(width 0.1)
		(layer "B.Cu")
		(net 192)
	)
	(segment
		(start 153.947966 93.077552)
		(end 154.02 93.077552)
		(width 0.1)
		(layer "B.Cu")
		(net 192)
	)
	(segment
		(start 154.02 93.877552)
		(end 153.57 93.877552)
		(width 0.1)
		(layer "B.Cu")
		(net 192)
	)
	(segment
		(start 152.577955 88.74998)
		(end 152.575 88.74998)
		(width 0.1)
		(layer "B.Cu")
		(net 192)
	)
	(segment
		(start 154.145 92.24)
		(end 153.786 91.881)
		(width 0.1)
		(layer "B.Cu")
		(net 192)
	)
	(segment
		(start 154.145 94.045)
		(end 154.145 94.002552)
		(width 0.1)
		(layer "B.Cu")
		(net 192)
	)
	(segment
		(start 154.025 96.15)
		(end 154.145 96.03)
		(width 0.1)
		(layer "B.Cu")
		(net 192)
	)
	(segment
		(start 153.786 89.958025)
		(end 152.577955 88.74998)
		(width 0.1)
		(layer "B.Cu")
		(net 192)
	)
	(segment
		(start 153.57 94.17)
		(end 154.02 94.17)
		(width 0.1)
		(layer "B.Cu")
		(net 192)
	)
	(segment
		(start 154.145 93.502552)
		(end 154.145 93.452552)
		(width 0.1)
		(layer "B.Cu")
		(net 192)
	)
	(segment
		(start 154.275 97.025)
		(end 154.275 96.680025)
		(width 0.1)
		(layer "B.Cu")
		(net 192)
	)
	(segment
		(start 154.02 94.42)
		(end 153.57 94.42)
		(width 0.1)
		(layer "B.Cu")
		(net 192)
	)
	(segment
		(start 154.02 93.327552)
		(end 153.947966 93.327552)
		(width 0.1)
		(layer "B.Cu")
		(net 192)
	)
	(segment
		(start 153.786 91.881)
		(end 153.786 89.958025)
		(width 0.1)
		(layer "B.Cu")
		(net 192)
	)
	(segment
		(start 154.145 92.902552)
		(end 154.145 92.24)
		(width 0.1)
		(layer "B.Cu")
		(net 192)
	)
	(arc
		(start 154.145 94.545)
		(mid 154.108388 94.456612)
		(end 154.02 94.42)
		(width 0.1)
		(layer "B.Cu")
		(net 192)
	)
	(arc
		(start 154.145 94.002552)
		(mid 154.108388 93.914164)
		(end 154.02 93.877552)
		(width 0.1)
		(layer "B.Cu")
		(net 192)
	)
	(arc
		(start 153.947966 93.327552)
		(mid 153.859578 93.29094)
		(end 153.822966 93.202552)
		(width 0.1)
		(layer "B.Cu")
		(net 192)
	)
	(arc
		(start 153.445 94.295)
		(mid 153.481612 94.206612)
		(end 153.57 94.17)
		(width 0.1)
		(layer "B.Cu")
		(net 192)
	)
	(arc
		(start 153.822966 93.202552)
		(mid 153.859578 93.114164)
		(end 153.947966 93.077552)
		(width 0.1)
		(layer "B.Cu")
		(net 192)
	)
	(arc
		(start 154.02 94.17)
		(mid 154.108388 94.133388)
		(end 154.145 94.045)
		(width 0.1)
		(layer "B.Cu")
		(net 192)
	)
	(arc
		(start 153.445 93.752552)
		(mid 153.481612 93.664164)
		(end 153.57 93.627552)
		(width 0.1)
		(layer "B.Cu")
		(net 192)
	)
	(arc
		(start 153.57 94.42)
		(mid 153.481612 94.383388)
		(end 153.445 94.295)
		(width 0.1)
		(layer "B.Cu")
		(net 192)
	)
	(arc
		(start 154.145 93.452552)
		(mid 154.108388 93.364164)
		(end 154.02 93.327552)
		(width 0.1)
		(layer "B.Cu")
		(net 192)
	)
	(arc
		(start 153.57 93.877552)
		(mid 153.481612 93.84094)
		(end 153.445 93.752552)
		(width 0.1)
		(layer "B.Cu")
		(net 192)
	)
	(arc
		(start 154.02 93.627552)
		(mid 154.108388 93.59094)
		(end 154.145 93.502552)
		(width 0.1)
		(layer "B.Cu")
		(net 192)
	)
	(arc
		(start 154.02 93.077552)
		(mid 154.108388 93.04094)
		(end 154.145 92.952552)
		(width 0.1)
		(layer "B.Cu")
		(net 192)
	)
	(segment
		(start 152.975 90.35)
		(end 153.075 90.35)
		(width 0.1)
		(layer "F.Cu")
		(net 193)
	)
	(segment
		(start 153.075 90.35)
		(end 153.375 90.65)
		(width 0.1)
		(layer "F.Cu")
		(net 193)
	)
	(segment
		(start 154.925 98.7)
		(end 154.925 96.825)
		(width 0.2)
		(layer "F.Cu")
		(net 193)
	)
	(via
		(at 153.375 90.65)
		(size 0.4)
		(drill 0.15)
		(layers "F.Cu" "B.Cu")
		(net 193)
	)
	(via
		(at 154.925 96.825)
		(size 0.4)
		(drill 0.15)
		(layers "F.Cu" "B.Cu")
		(net 193)
	)
	(segment
		(start 153.640431 91.591675)
		(end 153.707842 91.524263)
		(width 0.1)
		(layer "In2.Cu")
		(net 193)
	)
	(segment
		(start 153.566422 91.100001)
		(end 153.669187 90.997233)
		(width 0.1)
		(layer "In2.Cu")
		(net 193)
	)
	(segment
		(start 153.849263 91.524264)
		(end 153.849263 91.524263)
		(width 0.1)
		(layer "In2.Cu")
		(net 193)
	)
	(segment
		(start 153.849263 91.524263)
		(end 154.675 92.35)
		(width 0.1)
		(layer "In2.Cu")
		(net 193)
	)
	(segment
		(start 153.640431 91.591674)
		(end 153.640431 91.591675)
		(width 0.1)
		(layer "In2.Cu")
		(net 193)
	)
	(segment
		(start 153.375 90.65)
		(end 153.375 91.05)
		(width 0.1)
		(layer "In2.Cu")
		(net 193)
	)
	(segment
		(start 153.810608 91.138654)
		(end 153.81061 91.138655)
		(width 0.1)
		(layer "In2.Cu")
		(net 193)
	)
	(segment
		(start 153.566421 91.099999)
		(end 153.566422 91.100001)
		(width 0.1)
		(layer "In2.Cu")
		(net 193)
	)
	(segment
		(start 154.925 95.75)
		(end 154.925 96.825)
		(width 0.1)
		(layer "In2.Cu")
		(net 193)
	)
	(segment
		(start 153.499009 91.591674)
		(end 153.49901 91.591675)
		(width 0.1)
		(layer "In2.Cu")
		(net 193)
	)
	(segment
		(start 154.675 92.35)
		(end 154.675 95.5)
		(width 0.1)
		(layer "In2.Cu")
		(net 193)
	)
	(segment
		(start 153.375 91.05)
		(end 153.425 91.1)
		(width 0.1)
		(layer "In2.Cu")
		(net 193)
	)
	(segment
		(start 153.81061 91.138655)
		(end 153.49901 91.450253)
		(width 0.1)
		(layer "In2.Cu")
		(net 193)
	)
	(segment
		(start 154.675 95.5)
		(end 154.925 95.75)
		(width 0.1)
		(layer "In2.Cu")
		(net 193)
	)
	(arc
		(start 153.810609 90.997233)
		(mid 153.839898 91.067944)
		(end 153.810608 91.138654)
		(width 0.1)
		(layer "In2.Cu")
		(net 193)
	)
	(arc
		(start 153.707842 91.524263)
		(mid 153.778553 91.494974)
		(end 153.849263 91.524264)
		(width 0.1)
		(layer "In2.Cu")
		(net 193)
	)
	(arc
		(start 153.49901 91.591675)
		(mid 153.569721 91.620964)
		(end 153.640431 91.591674)
		(width 0.1)
		(layer "In2.Cu")
		(net 193)
	)
	(arc
		(start 153.669187 90.997233)
		(mid 153.739898 90.967944)
		(end 153.810609 90.997233)
		(width 0.1)
		(layer "In2.Cu")
		(net 193)
	)
	(arc
		(start 153.49901 91.450253)
		(mid 153.46972 91.520963)
		(end 153.499009 91.591674)
		(width 0.1)
		(layer "In2.Cu")
		(net 193)
	)
	(arc
		(start 153.425 91.1)
		(mid 153.495711 91.129289)
		(end 153.566421 91.099999)
		(width 0.1)
		(layer "In2.Cu")
		(net 193)
	)
	(segment
		(start 152.975 87.75)
		(end 153.075 87.75)
		(width 0.1)
		(layer "F.Cu")
		(net 194)
	)
	(segment
		(start 153.075 87.75)
		(end 153.375 88.05)
		(width 0.1)
		(layer "F.Cu")
		(net 194)
	)
	(via
		(at 153.375 88.05)
		(size 0.4)
		(drill 0.15)
		(layers "F.Cu" "B.Cu")
		(net 194)
	)
	(segment
		(start 154.8 93.75)
		(end 155.174581 93.75)
		(width 0.1)
		(layer "B.Cu")
		(net 194)
	)
	(segment
		(start 154.675 89.95)
		(end 154.675 93.625)
		(width 0.1)
		(layer "B.Cu")
		(net 194)
	)
	(segment
		(start 154.675 94.725)
		(end 154.675 94.775)
		(width 0.1)
		(layer "B.Cu")
		(net 194)
	)
	(segment
		(start 154.675 94.775)
		(end 154.675 95)
		(width 0.1)
		(layer "B.Cu")
		(net 194)
	)
	(segment
		(start 154.675 94.175)
		(end 154.675 94.225)
		(width 0.1)
		(layer "B.Cu")
		(net 194)
	)
	(segment
		(start 153.375 88.05)
		(end 153.775 88.45)
		(width 0.1)
		(layer "B.Cu")
		(net 194)
	)
	(segment
		(start 154.825 96.430025)
		(end 154.575 96.680025)
		(width 0.1)
		(layer "B.Cu")
		(net 194)
	)
	(segment
		(start 154.575 97.15)
		(end 154.675 97.25)
		(width 0.1)
		(layer "B.Cu")
		(net 194)
	)
	(segment
		(start 154.825 95.15)
		(end 154.825 96.430025)
		(width 0.1)
		(layer "B.Cu")
		(net 194)
	)
	(segment
		(start 154.675 95)
		(end 154.825 95.15)
		(width 0.1)
		(layer "B.Cu")
		(net 194)
	)
	(segment
		(start 153.775 88.45)
		(end 153.775 89.05)
		(width 0.1)
		(layer "B.Cu")
		(net 194)
	)
	(segment
		(start 154.675 97.25)
		(end 154.675 98.7)
		(width 0.1)
		(layer "B.Cu")
		(net 194)
	)
	(segment
		(start 154.8 94.35)
		(end 155.25 94.35)
		(width 0.1)
		(layer "B.Cu")
		(net 194)
	)
	(segment
		(start 153.775 89.05)
		(end 154.675 89.95)
		(width 0.1)
		(layer "B.Cu")
		(net 194)
	)
	(segment
		(start 155.25 94.6)
		(end 154.8 94.6)
		(width 0.1)
		(layer "B.Cu")
		(net 194)
	)
	(segment
		(start 155.174581 94)
		(end 154.8 94)
		(width 0.1)
		(layer "B.Cu")
		(net 194)
	)
	(segment
		(start 154.675 94.125)
		(end 154.675 94.175)
		(width 0.1)
		(layer "B.Cu")
		(net 194)
	)
	(segment
		(start 154.575 96.680025)
		(end 154.575 97.15)
		(width 0.1)
		(layer "B.Cu")
		(net 194)
	)
	(arc
		(start 155.299581 93.875)
		(mid 155.262969 93.963388)
		(end 155.174581 94)
		(width 0.1)
		(layer "B.Cu")
		(net 194)
	)
	(arc
		(start 155.25 94.35)
		(mid 155.338388 94.386612)
		(end 155.375 94.475)
		(width 0.1)
		(layer "B.Cu")
		(net 194)
	)
	(arc
		(start 154.675 93.625)
		(mid 154.711612 93.713388)
		(end 154.8 93.75)
		(width 0.1)
		(layer "B.Cu")
		(net 194)
	)
	(arc
		(start 154.8 94)
		(mid 154.711612 94.036612)
		(end 154.675 94.125)
		(width 0.1)
		(layer "B.Cu")
		(net 194)
	)
	(arc
		(start 155.174581 93.75)
		(mid 155.262969 93.786612)
		(end 155.299581 93.875)
		(width 0.1)
		(layer "B.Cu")
		(net 194)
	)
	(arc
		(start 155.375 94.475)
		(mid 155.338388 94.563388)
		(end 155.25 94.6)
		(width 0.1)
		(layer "B.Cu")
		(net 194)
	)
	(arc
		(start 154.8 94.6)
		(mid 154.711612 94.636612)
		(end 154.675 94.725)
		(width 0.1)
		(layer "B.Cu")
		(net 194)
	)
	(arc
		(start 154.675 94.225)
		(mid 154.711612 94.313388)
		(end 154.8 94.35)
		(width 0.1)
		(layer "B.Cu")
		(net 194)
	)
	(segment
		(start 155.425 98.7)
		(end 155.425 96.325)
		(width 0.2)
		(layer "F.Cu")
		(net 195)
	)
	(segment
		(start 153.033 89.7)
		(end 153.373 90.04)
		(width 0.1)
		(layer "F.Cu")
		(net 195)
	)
	(segment
		(start 152.975 89.7)
		(end 153.033 89.7)
		(width 0.1)
		(layer "F.Cu")
		(net 195)
	)
	(via
		(at 155.425 96.325)
		(size 0.4)
		(drill 0.15)
		(layers "F.Cu" "B.Cu")
		(net 195)
	)
	(via
		(at 153.373 90.04)
		(size 0.4)
		(drill 0.15)
		(layers "F.Cu" "B.Cu")
		(net 195)
	)
	(segment
		(start 155.425 96.325)
		(end 155.425 95.325)
		(width 0.1)
		(layer "In2.Cu")
		(net 195)
	)
	(segment
		(start 155.425 95.325)
		(end 155.075 94.975)
		(width 0.1)
		(layer "In2.Cu")
		(net 195)
	)
	(segment
		(start 155.075 91.42)
		(end 154.295 90.64)
		(width 0.1)
		(layer "In2.Cu")
		(net 195)
	)
	(segment
		(start 155.075 94.975)
		(end 155.075 91.42)
		(width 0.1)
		(layer "In2.Cu")
		(net 195)
	)
	(segment
		(start 153.973 90.64)
		(end 153.373 90.04)
		(width 0.1)
		(layer "In2.Cu")
		(net 195)
	)
	(segment
		(start 154.295 90.64)
		(end 153.973 90.64)
		(width 0.1)
		(layer "In2.Cu")
		(net 195)
	)
	(segment
		(start 152.225 91)
		(end 152.175 91)
		(width 0.1)
		(layer "F.Cu")
		(net 196)
	)
	(segment
		(start 152.258876 91)
		(end 152.593241 90.665635)
		(width 0.1)
		(layer "F.Cu")
		(net 196)
	)
	(segment
		(start 153.425 98.7)
		(end 153.425 96.325)
		(width 0.2)
		(layer "F.Cu")
		(net 196)
	)
	(via
		(at 152.593241 90.665635)
		(size 0.4)
		(drill 0.15)
		(layers "F.Cu" "B.Cu")
		(net 196)
	)
	(via
		(at 153.425 96.325)
		(size 0.4)
		(drill 0.15)
		(layers "F.Cu" "B.Cu")
		(net 196)
	)
	(segment
		(start 152.393242 90.865634)
		(end 152.593241 90.665635)
		(width 0.1)
		(layer "In2.Cu")
		(net 196)
	)
	(segment
		(start 153.32713 94.3)
		(end 153.225 94.3)
		(width 0.1)
		(layer "In2.Cu")
		(net 196)
	)
	(segment
		(start 153.125 96.025)
		(end 153.425 96.325)
		(width 0.1)
		(layer "In2.Cu")
		(net 196)
	)
	(segment
		(start 153.125 94.2)
		(end 153.125 93.75)
		(width 0.1)
		(layer "In2.Cu")
		(net 196)
	)
	(segment
		(start 153.125 93.75)
		(end 153.125 93.517144)
		(width 0.1)
		(layer "In2.Cu")
		(net 196)
	)
	(segment
		(start 153.125 96)
		(end 153.125 95.4)
		(width 0.1)
		(layer "In2.Cu")
		(net 196)
	)
	(segment
		(start 153.27713 95.1)
		(end 153.225 95.1)
		(width 0.1)
		(layer "In2.Cu")
		(net 196)
	)
	(segment
		(start 153.32713 94.7)
		(end 153.225 94.7)
		(width 0.1)
		(layer "In2.Cu")
		(net 196)
	)
	(segment
		(start 153.225 94.9)
		(end 153.32713 94.9)
		(width 0.1)
		(layer "In2.Cu")
		(net 196)
	)
	(segment
		(start 152.393242 92.785386)
		(end 152.393242 90.865634)
		(width 0.1)
		(layer "In2.Cu")
		(net 196)
	)
	(segment
		(start 153.225 95.3)
		(end 153.27713 95.3)
		(width 0.1)
		(layer "In2.Cu")
		(net 196)
	)
	(segment
		(start 153.225 94.5)
		(end 153.32713 94.5)
		(width 0.1)
		(layer "In2.Cu")
		(net 196)
	)
	(segment
		(start 153.125 93.517144)
		(end 152.393242 92.785386)
		(width 0.1)
		(layer "In2.Cu")
		(net 196)
	)
	(arc
		(start 153.225 94.7)
		(mid 153.154289 94.670711)
		(end 153.125 94.6)
		(width 0.1)
		(layer "In2.Cu")
		(net 196)
	)
	(arc
		(start 153.225 94.3)
		(mid 153.154289 94.270711)
		(end 153.125 94.2)
		(width 0.1)
		(layer "In2.Cu")
		(net 196)
	)
	(arc
		(start 153.125 95.4)
		(mid 153.154289 95.329289)
		(end 153.225 95.3)
		(width 0.1)
		(layer "In2.Cu")
		(net 196)
	)
	(arc
		(start 153.42713 94.4)
		(mid 153.397841 94.329289)
		(end 153.32713 94.3)
		(width 0.1)
		(layer "In2.Cu")
		(net 196)
	)
	(arc
		(start 153.27713 95.3)
		(mid 153.347841 95.270711)
		(end 153.37713 95.2)
		(width 0.1)
		(layer "In2.Cu")
		(net 196)
	)
	(arc
		(start 153.125 94.6)
		(mid 153.154289 94.529289)
		(end 153.225 94.5)
		(width 0.1)
		(layer "In2.Cu")
		(net 196)
	)
	(arc
		(start 153.42713 94.8)
		(mid 153.397841 94.729289)
		(end 153.32713 94.7)
		(width 0.1)
		(layer "In2.Cu")
		(net 196)
	)
	(arc
		(start 153.32713 94.9)
		(mid 153.397841 94.870711)
		(end 153.42713 94.8)
		(width 0.1)
		(layer "In2.Cu")
		(net 196)
	)
	(arc
		(start 153.32713 94.5)
		(mid 153.397841 94.470711)
		(end 153.42713 94.4)
		(width 0.1)
		(layer "In2.Cu")
		(net 196)
	)
	(arc
		(start 153.225 95.1)
		(mid 153.154289 95.070711)
		(end 153.125 95)
		(width 0.1)
		(layer "In2.Cu")
		(net 196)
	)
	(arc
		(start 153.37713 95.2)
		(mid 153.347841 95.129289)
		(end 153.27713 95.1)
		(width 0.1)
		(layer "In2.Cu")
		(net 196)
	)
	(arc
		(start 153.125 95)
		(mid 153.154289 94.929289)
		(end 153.225 94.9)
		(width 0.1)
		(layer "In2.Cu")
		(net 196)
	)
	(segment
		(start 152.125 90.35)
		(end 151.77502 90.69998)
		(width 0.1)
		(layer "F.Cu")
		(net 197)
	)
	(segment
		(start 152.175 90.35)
		(end 152.125 90.35)
		(width 0.1)
		(layer "F.Cu")
		(net 197)
	)
	(segment
		(start 152.925 98.7)
		(end 152.925 96.825)
		(width 0.2)
		(layer "F.Cu")
		(net 197)
	)
	(via
		(at 151.775 90.69998)
		(size 0.4)
		(drill 0.15)
		(layers "F.Cu" "B.Cu")
		(net 197)
	)
	(via
		(at 152.925 96.825)
		(size 0.4)
		(drill 0.15)
		(layers "F.Cu" "B.Cu")
		(net 197)
	)
	(segment
		(start 152.736018 95)
		(end 152.825 95)
		(width 0.1)
		(layer "In2.Cu")
		(net 197)
	)
	(segment
		(start 152.925 93.6)
		(end 152.175 92.85)
		(width 0.1)
		(layer "In2.Cu")
		(net 197)
	)
	(segment
		(start 152.825 96)
		(end 152.736018 96)
		(width 0.1)
		(layer "In2.Cu")
		(net 197)
	)
	(segment
		(start 152.175 92.85)
		(end 152.175 91.09998)
		(width 0.1)
		(layer "In2.Cu")
		(net 197)
	)
	(segment
		(start 152.825 95.6)
		(end 152.736018 95.6)
		(width 0.1)
		(layer "In2.Cu")
		(net 197)
	)
	(segment
		(start 152.925 94.45)
		(end 152.925 93.6)
		(width 0.1)
		(layer "In2.Cu")
		(net 197)
	)
	(segment
		(start 152.925 94.9)
		(end 152.925 94.45)
		(width 0.1)
		(layer "In2.Cu")
		(net 197)
	)
	(segment
		(start 152.736018 95.4)
		(end 152.825 95.4)
		(width 0.1)
		(layer "In2.Cu")
		(net 197)
	)
	(segment
		(start 152.736018 95.8)
		(end 152.825 95.8)
		(width 0.1)
		(layer "In2.Cu")
		(net 197)
	)
	(segment
		(start 152.825 95.2)
		(end 152.736018 95.2)
		(width 0.1)
		(layer "In2.Cu")
		(net 197)
	)
	(segment
		(start 152.175 91.09998)
		(end 151.775 90.69998)
		(width 0.1)
		(layer "In2.Cu")
		(net 197)
	)
	(segment
		(start 152.925 96.825)
		(end 152.925 96.1)
		(width 0.1)
		(layer "In2.Cu")
		(net 197)
	)
	(arc
		(start 152.925 96.1)
		(mid 152.895711 96.029289)
		(end 152.825 96)
		(width 0.1)
		(layer "In2.Cu")
		(net 197)
	)
	(arc
		(start 152.636018 95.5)
		(mid 152.665307 95.429289)
		(end 152.736018 95.4)
		(width 0.1)
		(layer "In2.Cu")
		(net 197)
	)
	(arc
		(start 152.825 95.8)
		(mid 152.895711 95.770711)
		(end 152.925 95.7)
		(width 0.1)
		(layer "In2.Cu")
		(net 197)
	)
	(arc
		(start 152.636018 95.9)
		(mid 152.665307 95.829289)
		(end 152.736018 95.8)
		(width 0.1)
		(layer "In2.Cu")
		(net 197)
	)
	(arc
		(start 152.636018 95.1)
		(mid 152.665307 95.029289)
		(end 152.736018 95)
		(width 0.1)
		(layer "In2.Cu")
		(net 197)
	)
	(arc
		(start 152.736018 96)
		(mid 152.665307 95.970711)
		(end 152.636018 95.9)
		(width 0.1)
		(layer "In2.Cu")
		(net 197)
	)
	(arc
		(start 152.825 95)
		(mid 152.895711 94.970711)
		(end 152.925 94.9)
		(width 0.1)
		(layer "In2.Cu")
		(net 197)
	)
	(arc
		(start 152.825 95.4)
		(mid 152.895711 95.370711)
		(end 152.925 95.3)
		(width 0.1)
		(layer "In2.Cu")
		(net 197)
	)
	(arc
		(start 152.925 95.7)
		(mid 152.895711 95.629289)
		(end 152.825 95.6)
		(width 0.1)
		(layer "In2.Cu")
		(net 197)
	)
	(arc
		(start 152.736018 95.2)
		(mid 152.665307 95.170711)
		(end 152.636018 95.1)
		(width 0.1)
		(layer "In2.Cu")
		(net 197)
	)
	(arc
		(start 152.925 95.3)
		(mid 152.895711 95.229289)
		(end 152.825 95.2)
		(width 0.1)
		(layer "In2.Cu")
		(net 197)
	)
	(arc
		(start 152.736018 95.6)
		(mid 152.665307 95.570711)
		(end 152.636018 95.5)
		(width 0.1)
		(layer "In2.Cu")
		(net 197)
	)
	(segment
		(start 151.325 92.3)
		(end 150.97502 92.64998)
		(width 0.1)
		(layer "F.Cu")
		(net 198)
	)
	(segment
		(start 151.375 92.3)
		(end 151.325 92.3)
		(width 0.1)
		(layer "F.Cu")
		(net 198)
	)
	(segment
		(start 151.425 98.7)
		(end 151.425 96.325)
		(width 0.2)
		(layer "F.Cu")
		(net 198)
	)
	(via
		(at 151.425 96.325)
		(size 0.4)
		(drill 0.15)
		(layers "F.Cu" "B.Cu")
		(net 198)
	)
	(via
		(at 150.975 92.64998)
		(size 0.4)
		(drill 0.15)
		(layers "F.Cu" "B.Cu")
		(net 198)
	)
	(segment
		(start 151.3 95.935)
		(end 151.2631 95.935)
		(width 0.1)
		(layer "In2.Cu")
		(net 198)
	)
	(segment
		(start 151.425 94.594637)
		(end 151.425 93.09998)
		(width 0.1)
		(layer "In2.Cu")
		(net 198)
	)
	(segment
		(start 151.2631 95.685)
		(end 151.3 95.685)
		(width 0.1)
		(layer "In2.Cu")
		(net 198)
	)
	(segment
		(start 151.425 95.185)
		(end 151.9369 95.185)
		(width 0.1)
		(layer "In2.Cu")
		(net 198)
	)
	(segment
		(start 151.3 95.685)
		(end 151.9369 95.685)
		(width 0.1)
		(layer "In2.Cu")
		(net 198)
	)
	(segment
		(start 151.1131 95.185)
		(end 151.425 95.185)
		(width 0.1)
		(layer "In2.Cu")
		(net 198)
	)
	(segment
		(start 151.425 95.435)
		(end 151.1131 95.435)
		(width 0.1)
		(layer "In2.Cu")
		(net 198)
	)
	(segment
		(start 151.425 94.81)
		(end 151.425 94.594637)
		(width 0.1)
		(layer "In2.Cu")
		(net 198)
	)
	(segment
		(start 151.9369 94.935)
		(end 151.55 94.935)
		(width 0.1)
		(layer "In2.Cu")
		(net 198)
	)
	(segment
		(start 151.425 93.09998)
		(end 150.975 92.64998)
		(width 0.1)
		(layer "In2.Cu")
		(net 198)
	)
	(segment
		(start 151.425 96.325)
		(end 151.425 96.06)
		(width 0.1)
		(layer "In2.Cu")
		(net 198)
	)
	(segment
		(start 151.9369 95.435)
		(end 151.425 95.435)
		(width 0.1)
		(layer "In2.Cu")
		(net 198)
	)
	(arc
		(start 150.9881 95.31)
		(mid 151.024712 95.221612)
		(end 151.1131 95.185)
		(width 0.1)
		(layer "In2.Cu")
		(net 198)
	)
	(arc
		(start 151.2631 95.935)
		(mid 151.174712 95.898388)
		(end 151.1381 95.81)
		(width 0.1)
		(layer "In2.Cu")
		(net 198)
	)
	(arc
		(start 151.9369 95.685)
		(mid 152.025288 95.648388)
		(end 152.0619 95.56)
		(width 0.1)
		(layer "In2.Cu")
		(net 198)
	)
	(arc
		(start 151.425 96.06)
		(mid 151.388388 95.971612)
		(end 151.3 95.935)
		(width 0.1)
		(layer "In2.Cu")
		(net 198)
	)
	(arc
		(start 152.0619 95.06)
		(mid 152.025288 94.971612)
		(end 151.9369 94.935)
		(width 0.1)
		(layer "In2.Cu")
		(net 198)
	)
	(arc
		(start 151.9369 95.185)
		(mid 152.025288 95.148388)
		(end 152.0619 95.06)
		(width 0.1)
		(layer "In2.Cu")
		(net 198)
	)
	(arc
		(start 151.1131 95.435)
		(mid 151.024712 95.398388)
		(end 150.9881 95.31)
		(width 0.1)
		(layer "In2.Cu")
		(net 198)
	)
	(arc
		(start 152.0619 95.56)
		(mid 152.025288 95.471612)
		(end 151.9369 95.435)
		(width 0.1)
		(layer "In2.Cu")
		(net 198)
	)
	(arc
		(start 151.1381 95.81)
		(mid 151.174712 95.721612)
		(end 151.2631 95.685)
		(width 0.1)
		(layer "In2.Cu")
		(net 198)
	)
	(arc
		(start 151.55 94.935)
		(mid 151.461612 94.898388)
		(end 151.425 94.81)
		(width 0.1)
		(layer "In2.Cu")
		(net 198)
	)
	(segment
		(start 151.475 87.75)
		(end 151.775 88.05)
		(width 0.1)
		(layer "F.Cu")
		(net 199)
	)
	(segment
		(start 151.375 87.75)
		(end 151.475 87.75)
		(width 0.1)
		(layer "F.Cu")
		(net 199)
	)
	(via
		(at 151.775 88.05)
		(size 0.4)
		(drill 0.15)
		(layers "F.Cu" "B.Cu")
		(net 199)
	)
	(segment
		(start 152.597027 94.575)
		(end 152.825 94.575)
		(width 0.1)
		(layer "B.Cu")
		(net 199)
	)
	(segment
		(start 152.175 97.069975)
		(end 152.95 96.294975)
		(width 0.1)
		(layer "B.Cu")
		(net 199)
	)
	(segment
		(start 152.175 98.7)
		(end 152.175 97.069975)
		(width 0.1)
		(layer "B.Cu")
		(net 199)
	)
	(segment
		(start 153.075 95.075)
		(end 153.302973 95.075)
		(width 0.1)
		(layer "B.Cu")
		(net 199)
	)
	(segment
		(start 153.075 94.825)
		(end 152.597027 94.825)
		(width 0.1)
		(layer "B.Cu")
		(net 199)
	)
	(segment
		(start 152.95 94.45)
		(end 152.95 94.182711)
		(width 0.1)
		(layer "B.Cu")
		(net 199)
	)
	(segment
		(start 152.175 88.45)
		(end 151.775 88.05)
		(width 0.1)
		(layer "B.Cu")
		(net 199)
	)
	(segment
		(start 152.95 89.625)
		(end 152.2 88.875)
		(width 0.1)
		(layer "B.Cu")
		(net 199)
	)
	(segment
		(start 152.2 88.475)
		(end 151.775 88.05)
		(width 0.1)
		(layer "B.Cu")
		(net 199)
	)
	(segment
		(start 152.2 88.875)
		(end 152.2 88.475)
		(width 0.1)
		(layer "B.Cu")
		(net 199)
	)
	(segment
		(start 152.95 94.182711)
		(end 152.95 89.625)
		(width 0.1)
		(layer "B.Cu")
		(net 199)
	)
	(segment
		(start 153.302973 94.825)
		(end 153.075 94.825)
		(width 0.1)
		(layer "B.Cu")
		(net 199)
	)
	(segment
		(start 152.95 96.294975)
		(end 152.95 95.2)
		(width 0.1)
		(layer "B.Cu")
		(net 199)
	)
	(arc
		(start 153.302973 95.075)
		(mid 153.391361 95.038388)
		(end 153.427973 94.95)
		(width 0.1)
		(layer "B.Cu")
		(net 199)
	)
	(arc
		(start 152.472027 94.7)
		(mid 152.508639 94.611612)
		(end 152.597027 94.575)
		(width 0.1)
		(layer "B.Cu")
		(net 199)
	)
	(arc
		(start 153.427973 94.95)
		(mid 153.391361 94.861612)
		(end 153.302973 94.825)
		(width 0.1)
		(layer "B.Cu")
		(net 199)
	)
	(arc
		(start 152.825 94.575)
		(mid 152.913388 94.538388)
		(end 152.95 94.45)
		(width 0.1)
		(layer "B.Cu")
		(net 199)
	)
	(arc
		(start 152.95 95.2)
		(mid 152.986612 95.111612)
		(end 153.075 95.075)
		(width 0.1)
		(layer "B.Cu")
		(net 199)
	)
	(arc
		(start 152.597027 94.825)
		(mid 152.508639 94.788388)
		(end 152.472027 94.7)
		(width 0.1)
		(layer "B.Cu")
		(net 199)
	)
	(segment
		(start 151.475 88.4)
		(end 151.775 88.7)
		(width 0.1)
		(layer "F.Cu")
		(net 200)
	)
	(segment
		(start 151.375 88.4)
		(end 151.475 88.4)
		(width 0.1)
		(layer "F.Cu")
		(net 200)
	)
	(via
		(at 151.775 88.7)
		(size 0.4)
		(drill 0.15)
		(layers "F.Cu" "B.Cu")
		(net 200)
	)
	(segment
		(start 151.575 96.669975)
		(end 151.8625 96.382475)
		(width 0.1)
		(layer "B.Cu")
		(net 200)
	)
	(segment
		(start 152.535702 95.3625)
		(end 151.8625 95.3625)
		(width 0.1)
		(layer "B.Cu")
		(net 200)
	)
	(segment
		(start 152.175 93.125)
		(end 152.175 89.25)
		(width 0.1)
		(layer "B.Cu")
		(net 200)
	)
	(segment
		(start 151.7375 95.6125)
		(end 152.535702 95.6125)
		(width 0.1)
		(layer "B.Cu")
		(net 200)
	)
	(segment
		(start 151.8625 93.4375)
		(end 152.175 93.125)
		(width 0.1)
		(layer "B.Cu")
		(net 200)
	)
	(segment
		(start 151.575 97)
		(end 151.575 96.669975)
		(width 0.1)
		(layer "B.Cu")
		(net 200)
	)
	(segment
		(start 151.675 97.1)
		(end 151.575 97)
		(width 0.1)
		(layer "B.Cu")
		(net 200)
	)
	(segment
		(start 151.8625 94.741533)
		(end 151.8625 93.4375)
		(width 0.1)
		(layer "B.Cu")
		(net 200)
	)
	(segment
		(start 151.775 88.85)
		(end 151.775 88.7)
		(width 0.1)
		(layer "B.Cu")
		(net 200)
	)
	(segment
		(start 151.7375 95.8625)
		(end 151.489298 95.8625)
		(width 0.1)
		(layer "B.Cu")
		(net 200)
	)
	(segment
		(start 151.8625 94.9875)
		(end 151.8625 94.741533)
		(width 0.1)
		(layer "B.Cu")
		(net 200)
	)
	(segment
		(start 151.489298 95.1125)
		(end 151.7375 95.1125)
		(width 0.1)
		(layer "B.Cu")
		(net 200)
	)
	(segment
		(start 151.489298 95.6125)
		(end 151.7375 95.6125)
		(width 0.1)
		(layer "B.Cu")
		(net 200)
	)
	(segment
		(start 151.8625 96.382475)
		(end 151.8625 95.9875)
		(width 0.1)
		(layer "B.Cu")
		(net 200)
	)
	(segment
		(start 151.675 98.7)
		(end 151.675 97.1)
		(width 0.1)
		(layer "B.Cu")
		(net 200)
	)
	(segment
		(start 152.175 89.25)
		(end 151.775 88.85)
		(width 0.1)
		(layer "B.Cu")
		(net 200)
	)
	(segment
		(start 151.8625 95.3625)
		(end 151.489298 95.3625)
		(width 0.1)
		(layer "B.Cu")
		(net 200)
	)
	(arc
		(start 151.7375 95.1125)
		(mid 151.825888 95.075888)
		(end 151.8625 94.9875)
		(width 0.1)
		(layer "B.Cu")
		(net 200)
	)
	(arc
		(start 151.8625 95.9875)
		(mid 151.825888 95.899112)
		(end 151.7375 95.8625)
		(width 0.1)
		(layer "B.Cu")
		(net 200)
	)
	(arc
		(start 151.489298 95.3625)
		(mid 151.40091 95.325888)
		(end 151.364298 95.2375)
		(width 0.1)
		(layer "B.Cu")
		(net 200)
	)
	(arc
		(start 151.364298 95.7375)
		(mid 151.40091 95.649112)
		(end 151.489298 95.6125)
		(width 0.1)
		(layer "B.Cu")
		(net 200)
	)
	(arc
		(start 152.535702 95.6125)
		(mid 152.62409 95.575888)
		(end 152.660702 95.4875)
		(width 0.1)
		(layer "B.Cu")
		(net 200)
	)
	(arc
		(start 151.489298 95.8625)
		(mid 151.40091 95.825888)
		(end 151.364298 95.7375)
		(width 0.1)
		(layer "B.Cu")
		(net 200)
	)
	(arc
		(start 152.660702 95.4875)
		(mid 152.62409 95.399112)
		(end 152.535702 95.3625)
		(width 0.1)
		(layer "B.Cu")
		(net 200)
	)
	(arc
		(start 151.364298 95.2375)
		(mid 151.40091 95.149112)
		(end 151.489298 95.1125)
		(width 0.1)
		(layer "B.Cu")
		(net 200)
	)
	(segment
		(start 152.175 91.65)
		(end 152.125 91.65)
		(width 0.1)
		(layer "F.Cu")
		(net 201)
	)
	(segment
		(start 152.125 91.65)
		(end 151.77502 91.99998)
		(width 0.1)
		(layer "F.Cu")
		(net 201)
	)
	(segment
		(start 152.425 98.7)
		(end 152.425 96.325)
		(width 0.2)
		(layer "F.Cu")
		(net 201)
	)
	(via
		(at 151.775 91.99998)
		(size 0.4)
		(drill 0.15)
		(layers "F.Cu" "B.Cu")
		(net 201)
	)
	(via
		(at 152.425 96.325)
		(size 0.4)
		(drill 0.15)
		(layers "F.Cu" "B.Cu")
		(net 201)
	)
	(segment
		(start 152.425 93.83)
		(end 152.425 93.7)
		(width 0.1)
		(layer "In2.Cu")
		(net 201)
	)
	(segment
		(start 152.425 93.7)
		(end 151.775 93.05)
		(width 0.1)
		(layer "In2.Cu")
		(net 201)
	)
	(segment
		(start 152.425 94.205)
		(end 151.890808 94.205)
		(width 0.1)
		(layer "In2.Cu")
		(net 201)
	)
	(segment
		(start 152.425 96.325)
		(end 152.425 94.83)
		(width 0.1)
		(layer "In2.Cu")
		(net 201)
	)
	(segment
		(start 151.890808 93.955)
		(end 152.3 93.955)
		(width 0.1)
		(layer "In2.Cu")
		(net 201)
	)
	(segment
		(start 151.890808 94.455)
		(end 152.3 94.455)
		(width 0.1)
		(layer "In2.Cu")
		(net 201)
	)
	(segment
		(start 151.775 93.05)
		(end 151.775 91.99998)
		(width 0.1)
		(layer "In2.Cu")
		(net 201)
	)
	(segment
		(start 152.3 94.455)
		(end 152.559192 94.455)
		(width 0.1)
		(layer "In2.Cu")
		(net 201)
	)
	(segment
		(start 152.3 94.705)
		(end 151.890808 94.705)
		(width 0.1)
		(layer "In2.Cu")
		(net 201)
	)
	(segment
		(start 152.559192 94.205)
		(end 152.425 94.205)
		(width 0.1)
		(layer "In2.Cu")
		(net 201)
	)
	(arc
		(start 152.425 94.83)
		(mid 152.388388 94.741612)
		(end 152.3 94.705)
		(width 0.1)
		(layer "In2.Cu")
		(net 201)
	)
	(arc
		(start 151.890808 94.205)
		(mid 151.80242 94.168388)
		(end 151.765808 94.08)
		(width 0.1)
		(layer "In2.Cu")
		(net 201)
	)
	(arc
		(start 151.765808 94.08)
		(mid 151.80242 93.991612)
		(end 151.890808 93.955)
		(width 0.1)
		(layer "In2.Cu")
		(net 201)
	)
	(arc
		(start 152.3 93.955)
		(mid 152.388388 93.918388)
		(end 152.425 93.83)
		(width 0.1)
		(layer "In2.Cu")
		(net 201)
	)
	(arc
		(start 152.559192 94.455)
		(mid 152.64758 94.418388)
		(end 152.684192 94.33)
		(width 0.1)
		(layer "In2.Cu")
		(net 201)
	)
	(arc
		(start 151.890808 94.705)
		(mid 151.80242 94.668388)
		(end 151.765808 94.58)
		(width 0.1)
		(layer "In2.Cu")
		(net 201)
	)
	(arc
		(start 151.765808 94.58)
		(mid 151.80242 94.491612)
		(end 151.890808 94.455)
		(width 0.1)
		(layer "In2.Cu")
		(net 201)
	)
	(arc
		(start 152.684192 94.33)
		(mid 152.64758 94.241612)
		(end 152.559192 94.205)
		(width 0.1)
		(layer "In2.Cu")
		(net 201)
	)
	(segment
		(start 151.375 91.65)
		(end 151.325 91.65)
		(width 0.1)
		(layer "F.Cu")
		(net 202)
	)
	(segment
		(start 151.325 91.65)
		(end 150.97502 91.99998)
		(width 0.1)
		(layer "F.Cu")
		(net 202)
	)
	(segment
		(start 150.925 98.7)
		(end 150.925 96.825)
		(width 0.2)
		(layer "F.Cu")
		(net 202)
	)
	(via
		(at 150.975 91.99998)
		(size 0.4)
		(drill 0.15)
		(layers "F.Cu" "B.Cu")
		(net 202)
	)
	(via
		(at 150.925 96.825)
		(size 0.4)
		(drill 0.15)
		(layers "F.Cu" "B.Cu")
		(net 202)
	)
	(segment
		(start 150.7 93.755)
		(end 151.012039 93.755)
		(width 0.1)
		(layer "In2.Cu")
		(net 202)
	)
	(segment
		(start 150.7 93.505)
		(end 150.337961 93.505)
		(width 0.1)
		(layer "In2.Cu")
		(net 202)
	)
	(segment
		(start 150.196445 94.871446)
		(end 150.196445 94.871445)
		(width 0.1)
		(layer "In2.Cu")
		(net 202)
	)
	(segment
		(start 150.575 93.13)
		(end 150.575 92.825379)
		(width 0.1)
		(layer "In2.Cu")
		(net 202)
	)
	(segment
		(start 150.549999 95.048223)
		(end 150.55 95.048223)
		(width 0.1)
		(layer "In2.Cu")
		(net 202)
	)
	(segment
		(start 150.55 95.048223)
		(end 150.726776 94.871446)
		(width 0.1)
		(layer "In2.Cu")
		(net 202)
	)
	(segment
		(start 150.575 92.39998)
		(end 150.975 91.99998)
		(width 0.1)
		(layer "In2.Cu")
		(net 202)
	)
	(segment
		(start 150.125 94.8)
		(end 150.125 94.33)
		(width 0.1)
		(layer "In2.Cu")
		(net 202)
	)
	(segment
		(start 151.012039 93.505)
		(end 150.7 93.505)
		(width 0.1)
		(layer "In2.Cu")
		(net 202)
	)
	(segment
		(start 150.575 92.825379)
		(end 150.575 92.39998)
		(width 0.1)
		(layer "In2.Cu")
		(net 202)
	)
	(segment
		(start 150.726777 94.694669)
		(end 150.726776 94.694669)
		(width 0.1)
		(layer "In2.Cu")
		(net 202)
	)
	(segment
		(start 150.125 94.33)
		(end 150.575 93.88)
		(width 0.1)
		(layer "In2.Cu")
		(net 202)
	)
	(segment
		(start 150.549999 94.694669)
		(end 150.373222 94.871445)
		(width 0.1)
		(layer "In2.Cu")
		(net 202)
	)
	(segment
		(start 150.196445 94.871445)
		(end 150.125 94.8)
		(width 0.1)
		(layer "In2.Cu")
		(net 202)
	)
	(segment
		(start 150.337961 93.255)
		(end 150.45 93.255)
		(width 0.1)
		(layer "In2.Cu")
		(net 202)
	)
	(segment
		(start 150.549999 94.694668)
		(end 150.549999 94.694669)
		(width 0.1)
		(layer "In2.Cu")
		(net 202)
	)
	(segment
		(start 150.925 95.6)
		(end 150.55 95.225)
		(width 0.1)
		(layer "In2.Cu")
		(net 202)
	)
	(segment
		(start 150.925 96.825)
		(end 150.925 95.6)
		(width 0.1)
		(layer "In2.Cu")
		(net 202)
	)
	(arc
		(start 150.45 93.255)
		(mid 150.538388 93.218388)
		(end 150.575 93.13)
		(width 0.1)
		(layer "In2.Cu")
		(net 202)
	)
	(arc
		(start 150.373222 94.871445)
		(mid 150.284834 94.908057)
		(end 150.196445 94.871446)
		(width 0.1)
		(layer "In2.Cu")
		(net 202)
	)
	(arc
		(start 150.337961 93.505)
		(mid 150.249573 93.468388)
		(end 150.212961 93.38)
		(width 0.1)
		(layer "In2.Cu")
		(net 202)
	)
	(arc
		(start 150.212961 93.38)
		(mid 150.249573 93.291612)
		(end 150.337961 93.255)
		(width 0.1)
		(layer "In2.Cu")
		(net 202)
	)
	(arc
		(start 150.726776 94.694669)
		(mid 150.638388 94.658057)
		(end 150.549999 94.694668)
		(width 0.1)
		(layer "In2.Cu")
		(net 202)
	)
	(arc
		(start 151.012039 93.755)
		(mid 151.100427 93.718388)
		(end 151.137039 93.63)
		(width 0.1)
		(layer "In2.Cu")
		(net 202)
	)
	(arc
		(start 150.575 93.88)
		(mid 150.611612 93.791612)
		(end 150.7 93.755)
		(width 0.1)
		(layer "In2.Cu")
		(net 202)
	)
	(arc
		(start 150.55 95.225)
		(mid 150.513388 95.136612)
		(end 150.549999 95.048223)
		(width 0.1)
		(layer "In2.Cu")
		(net 202)
	)
	(arc
		(start 151.137039 93.63)
		(mid 151.100427 93.541612)
		(end 151.012039 93.505)
		(width 0.1)
		(layer "In2.Cu")
		(net 202)
	)
	(arc
		(start 150.726776 94.871446)
		(mid 150.763388 94.783058)
		(end 150.726777 94.694669)
		(width 0.1)
		(layer "In2.Cu")
		(net 202)
	)
	(segment
		(start 150.425 98.7)
		(end 150.425 96.325)
		(width 0.2)
		(layer "F.Cu")
		(net 203)
	)
	(segment
		(start 151.325 90.35)
		(end 150.97502 90.69998)
		(width 0.1)
		(layer "F.Cu")
		(net 203)
	)
	(segment
		(start 151.375 90.35)
		(end 151.325 90.35)
		(width 0.1)
		(layer "F.Cu")
		(net 203)
	)
	(via
		(at 150.425 96.325)
		(size 0.4)
		(drill 0.15)
		(layers "F.Cu" "B.Cu")
		(net 203)
	)
	(via
		(at 150.975 90.69998)
		(size 0.4)
		(drill 0.15)
		(layers "F.Cu" "B.Cu")
		(net 203)
	)
	(segment
		(start 150.425 95.65)
		(end 150.425 96.325)
		(width 0.1)
		(layer "In2.Cu")
		(net 203)
	)
	(segment
		(start 149.85 93.525)
		(end 149.9 93.525)
		(width 0.1)
		(layer "In2.Cu")
		(net 203)
	)
	(segment
		(start 149.725 94.95)
		(end 150.425 95.65)
		(width 0.1)
		(layer "In2.Cu")
		(net 203)
	)
	(segment
		(start 150.975 90.69998)
		(end 150.975 91.2)
		(width 0.1)
		(layer "In2.Cu")
		(net 203)
	)
	(segment
		(start 149.961827 93.21)
		(end 149.825 93.21)
		(width 0.1)
		(layer "In2.Cu")
		(net 203)
	)
	(segment
		(start 149.725 93.9)
		(end 149.725 93.934027)
		(width 0.1)
		(layer "In2.Cu")
		(net 203)
	)
	(segment
		(start 149.725 93.359999)
		(end 149.725 93.4)
		(width 0.1)
		(layer "In2.Cu")
		(net 203)
	)
	(segment
		(start 149.725 92.45)
		(end 149.725 92.91)
		(width 0.1)
		(layer "In2.Cu")
		(net 203)
	)
	(segment
		(start 149.825 93.01)
		(end 149.961827 93.01)
		(width 0.1)
		(layer "In2.Cu")
		(net 203)
	)
	(segment
		(start 149.725 93.31)
		(end 149.725 93.359999)
		(width 0.1)
		(layer "In2.Cu")
		(net 203)
	)
	(segment
		(start 149.9 93.775)
		(end 149.85 93.775)
		(width 0.1)
		(layer "In2.Cu")
		(net 203)
	)
	(segment
		(start 150.975 91.2)
		(end 149.725 92.45)
		(width 0.1)
		(layer "In2.Cu")
		(net 203)
	)
	(segment
		(start 149.725 93.934027)
		(end 149.725 94.95)
		(width 0.1)
		(layer "In2.Cu")
		(net 203)
	)
	(arc
		(start 149.825 93.21)
		(mid 149.754289 93.239289)
		(end 149.725 93.31)
		(width 0.1)
		(layer "In2.Cu")
		(net 203)
	)
	(arc
		(start 150.025 93.65)
		(mid 149.988388 93.738388)
		(end 149.9 93.775)
		(width 0.1)
		(layer "In2.Cu")
		(net 203)
	)
	(arc
		(start 149.9 93.525)
		(mid 149.988388 93.561612)
		(end 150.025 93.65)
		(width 0.1)
		(layer "In2.Cu")
		(net 203)
	)
	(arc
		(start 149.961827 93.01)
		(mid 150.032538 93.039289)
		(end 150.061827 93.11)
		(width 0.1)
		(layer "In2.Cu")
		(net 203)
	)
	(arc
		(start 150.061827 93.11)
		(mid 150.032538 93.180711)
		(end 149.961827 93.21)
		(width 0.1)
		(layer "In2.Cu")
		(net 203)
	)
	(arc
		(start 149.725 93.4)
		(mid 149.761612 93.488388)
		(end 149.85 93.525)
		(width 0.1)
		(layer "In2.Cu")
		(net 203)
	)
	(arc
		(start 149.725 92.91)
		(mid 149.754289 92.980711)
		(end 149.825 93.01)
		(width 0.1)
		(layer "In2.Cu")
		(net 203)
	)
	(arc
		(start 149.85 93.775)
		(mid 149.761612 93.811612)
		(end 149.725 93.9)
		(width 0.1)
		(layer "In2.Cu")
		(net 203)
	)
	(segment
		(start 151.325 89.7)
		(end 150.97502 90.04998)
		(width 0.1)
		(layer "F.Cu")
		(net 204)
	)
	(segment
		(start 151.375 89.7)
		(end 151.325 89.7)
		(width 0.1)
		(layer "F.Cu")
		(net 204)
	)
	(segment
		(start 149.925 98.7)
		(end 149.925 96.825)
		(width 0.2)
		(layer "F.Cu")
		(net 204)
	)
	(via
		(at 150.975 90.04998)
		(size 0.4)
		(drill 0.15)
		(layers "F.Cu" "B.Cu")
		(net 204)
	)
	(via
		(at 149.925 96.825)
		(size 0.4)
		(drill 0.15)
		(layers "F.Cu" "B.Cu")
		(net 204)
	)
	(segment
		(start 150.17498 90.85)
		(end 150.975 90.04998)
		(width 0.1)
		(layer "In2.Cu")
		(net 204)
	)
	(segment
		(start 149.925 96.825)
		(end 149.925 95.75)
		(width 0.1)
		(layer "In2.Cu")
		(net 204)
	)
	(segment
		(start 149.42501 95.25001)
		(end 149.42501 91.26999)
		(width 0.1)
		(layer "In2.Cu")
		(net 204)
	)
	(segment
		(start 149.42501 91.26999)
		(end 149.845 90.85)
		(width 0.1)
		(layer "In2.Cu")
		(net 204)
	)
	(segment
		(start 149.845 90.85)
		(end 150.17498 90.85)
		(width 0.1)
		(layer "In2.Cu")
		(net 204)
	)
	(segment
		(start 149.925 95.75)
		(end 149.42501 95.25001)
		(width 0.1)
		(layer "In2.Cu")
		(net 204)
	)
	(segment
		(start 147.475 89.7)
		(end 147.775 90)
		(width 0.1)
		(layer "F.Cu")
		(net 205)
	)
	(segment
		(start 147.375 89.7)
		(end 147.475 89.7)
		(width 0.1)
		(layer "F.Cu")
		(net 205)
	)
	(segment
		(start 149.425 98.7)
		(end 149.425 96.325)
		(width 0.2)
		(layer "F.Cu")
		(net 205)
	)
	(via
		(at 147.775 90)
		(size 0.4)
		(drill 0.15)
		(layers "F.Cu" "B.Cu")
		(net 205)
	)
	(via
		(at 149.425 96.325)
		(size 0.4)
		(drill 0.15)
		(layers "F.Cu" "B.Cu")
		(net 205)
	)
	(segment
		(start 148.96661 90.804836)
		(end 148.96661 90.804835)
		(width 0.1)
		(layer "In2.Cu")
		(net 205)
	)
	(segment
		(start 148.95 90.998223)
		(end 148.96661 90.981612)
		(width 0.1)
		(layer "In2.Cu")
		(net 205)
	)
	(segment
		(start 148.789833 90.804835)
		(end 148.773222 90.821445)
		(width 0.1)
		(layer "In2.Cu")
		(net 205)
	)
	(segment
		(start 148.949999 90.998223)
		(end 148.95 90.998223)
		(width 0.1)
		(layer "In2.Cu")
		(net 205)
	)
	(segment
		(start 149.225 91.45)
		(end 148.95 91.175)
		(width 0.1)
		(layer "In2.Cu")
		(net 205)
	)
	(segment
		(start 148.789833 90.804834)
		(end 148.789833 90.804835)
		(width 0.1)
		(layer "In2.Cu")
		(net 205)
	)
	(segment
		(start 149.225 95.7)
		(end 149.225 91.45)
		(width 0.1)
		(layer "In2.Cu")
		(net 205)
	)
	(segment
		(start 149.425 96.325)
		(end 149.425 95.9)
		(width 0.1)
		(layer "In2.Cu")
		(net 205)
	)
	(segment
		(start 148.596445 90.821445)
		(end 147.775 90)
		(width 0.1)
		(layer "In2.Cu")
		(net 205)
	)
	(segment
		(start 149.425 95.9)
		(end 149.225 95.7)
		(width 0.1)
		(layer "In2.Cu")
		(net 205)
	)
	(segment
		(start 148.596446 90.821445)
		(end 148.596445 90.821445)
		(width 0.1)
		(layer "In2.Cu")
		(net 205)
	)
	(arc
		(start 148.96661 90.981612)
		(mid 149.003222 90.893224)
		(end 148.96661 90.804836)
		(width 0.1)
		(layer "In2.Cu")
		(net 205)
	)
	(arc
		(start 148.773222 90.821445)
		(mid 148.684834 90.858057)
		(end 148.596446 90.821445)
		(width 0.1)
		(layer "In2.Cu")
		(net 205)
	)
	(arc
		(start 148.96661 90.804835)
		(mid 148.878222 90.768223)
		(end 148.789833 90.804834)
		(width 0.1)
		(layer "In2.Cu")
		(net 205)
	)
	(arc
		(start 148.95 91.175)
		(mid 148.913388 91.086612)
		(end 148.949999 90.998223)
		(width 0.1)
		(layer "In2.Cu")
		(net 205)
	)
	(segment
		(start 148.925 98.7)
		(end 148.925 96.825)
		(width 0.2)
		(layer "F.Cu")
		(net 206)
	)
	(segment
		(start 147.375 90.35)
		(end 147.475 90.35)
		(width 0.1)
		(layer "F.Cu")
		(net 206)
	)
	(segment
		(start 147.475 90.35)
		(end 147.775 90.65)
		(width 0.1)
		(layer "F.Cu")
		(net 206)
	)
	(via
		(at 148.925 96.825)
		(size 0.4)
		(drill 0.15)
		(layers "F.Cu" "B.Cu")
		(net 206)
	)
	(via
		(at 147.775 90.65)
		(size 0.4)
		(drill 0.15)
		(layers "F.Cu" "B.Cu")
		(net 206)
	)
	(segment
		(start 148.8 95.1)
		(end 148.645325 95.1)
		(width 0.1)
		(layer "In2.Cu")
		(net 206)
	)
	(segment
		(start 148.171 91.046)
		(end 147.775 90.65)
		(width 0.1)
		(layer "In2.Cu")
		(net 206)
	)
	(segment
		(start 148.645325 95.35)
		(end 148.8 95.35)
		(width 0.1)
		(layer "In2.Cu")
		(net 206)
	)
	(segment
		(start 148.645325 94.85)
		(end 148.8 94.85)
		(width 0.1)
		(layer "In2.Cu")
		(net 206)
	)
	(segment
		(start 148.925 92.448)
		(end 148.171 91.694)
		(width 0.1)
		(layer "In2.Cu")
		(net 206)
	)
	(segment
		(start 148.171 91.694)
		(end 148.171 91.046)
		(width 0.1)
		(layer "In2.Cu")
		(net 206)
	)
	(segment
		(start 148.925 94.725)
		(end 148.925 94.675)
		(width 0.1)
		(layer "In2.Cu")
		(net 206)
	)
	(segment
		(start 148.925 96.825)
		(end 148.925 95.725)
		(width 0.1)
		(layer "In2.Cu")
		(net 206)
	)
	(segment
		(start 148.925 94.675)
		(end 148.925 92.448)
		(width 0.1)
		(layer "In2.Cu")
		(net 206)
	)
	(segment
		(start 148.8 95.6)
		(end 148.645325 95.6)
		(width 0.1)
		(layer "In2.Cu")
		(net 206)
	)
	(arc
		(start 148.8 95.35)
		(mid 148.888388 95.313388)
		(end 148.925 95.225)
		(width 0.1)
		(layer "In2.Cu")
		(net 206)
	)
	(arc
		(start 148.645325 95.6)
		(mid 148.556937 95.563388)
		(end 148.520325 95.475)
		(width 0.1)
		(layer "In2.Cu")
		(net 206)
	)
	(arc
		(start 148.520325 95.475)
		(mid 148.556937 95.386612)
		(end 148.645325 95.35)
		(width 0.1)
		(layer "In2.Cu")
		(net 206)
	)
	(arc
		(start 148.645325 95.1)
		(mid 148.556937 95.063388)
		(end 148.520325 94.975)
		(width 0.1)
		(layer "In2.Cu")
		(net 206)
	)
	(arc
		(start 148.8 94.85)
		(mid 148.888388 94.813388)
		(end 148.925 94.725)
		(width 0.1)
		(layer "In2.Cu")
		(net 206)
	)
	(arc
		(start 148.925 95.725)
		(mid 148.888388 95.636612)
		(end 148.8 95.6)
		(width 0.1)
		(layer "In2.Cu")
		(net 206)
	)
	(arc
		(start 148.925 95.225)
		(mid 148.888388 95.136612)
		(end 148.8 95.1)
		(width 0.1)
		(layer "In2.Cu")
		(net 206)
	)
	(arc
		(start 148.520325 94.975)
		(mid 148.556937 94.886612)
		(end 148.645325 94.85)
		(width 0.1)
		(layer "In2.Cu")
		(net 206)
	)
	(segment
		(start 147.375 91.65)
		(end 147.475 91.65)
		(width 0.1)
		(layer "F.Cu")
		(net 207)
	)
	(segment
		(start 147.475 91.65)
		(end 147.775 91.95)
		(width 0.1)
		(layer "F.Cu")
		(net 207)
	)
	(segment
		(start 148.425 98.7)
		(end 148.425 96.325)
		(width 0.2)
		(layer "F.Cu")
		(net 207)
	)
	(via
		(at 147.775 91.95)
		(size 0.4)
		(drill 0.15)
		(layers "F.Cu" "B.Cu")
		(net 207)
	)
	(via
		(at 148.425 96.325)
		(size 0.4)
		(drill 0.15)
		(layers "F.Cu" "B.Cu")
		(net 207)
	)
	(segment
		(start 148.175 93.125)
		(end 148.175 92.35)
		(width 0.1)
		(layer "In2.Cu")
		(net 207)
	)
	(segment
		(start 148.610275 93.675)
		(end 148.275 93.675)
		(width 0.1)
		(layer "In2.Cu")
		(net 207)
	)
	(segment
		(start 148.175 92.35)
		(end 147.775 91.95)
		(width 0.1)
		(layer "In2.Cu")
		(net 207)
	)
	(segment
		(start 148.425 96)
		(end 148.175 95.75)
		(width 0.1)
		(layer "In2.Cu")
		(net 207)
	)
	(segment
		(start 148.275 94.275)
		(end 148.610275 94.275)
		(width 0.1)
		(layer "In2.Cu")
		(net 207)
	)
	(segment
		(start 148.175 93.175)
		(end 148.175 93.125)
		(width 0.1)
		(layer "In2.Cu")
		(net 207)
	)
	(segment
		(start 148.610275 93.275)
		(end 148.275 93.275)
		(width 0.1)
		(layer "In2.Cu")
		(net 207)
	)
	(segment
		(start 148.275 93.875)
		(end 148.610275 93.875)
		(width 0.1)
		(layer "In2.Cu")
		(net 207)
	)
	(segment
		(start 148.175 95.75)
		(end 148.175 94.375)
		(width 0.1)
		(layer "In2.Cu")
		(net 207)
	)
	(segment
		(start 148.275 93.475)
		(end 148.610275 93.475)
		(width 0.1)
		(layer "In2.Cu")
		(net 207)
	)
	(segment
		(start 148.610275 94.075)
		(end 148.275 94.075)
		(width 0.1)
		(layer "In2.Cu")
		(net 207)
	)
	(segment
		(start 148.425 96.325)
		(end 148.425 96)
		(width 0.1)
		(layer "In2.Cu")
		(net 207)
	)
	(arc
		(start 148.710275 94.175)
		(mid 148.680986 94.104289)
		(end 148.610275 94.075)
		(width 0.1)
		(layer "In2.Cu")
		(net 207)
	)
	(arc
		(start 148.610275 94.275)
		(mid 148.680986 94.245711)
		(end 148.710275 94.175)
		(width 0.1)
		(layer "In2.Cu")
		(net 207)
	)
	(arc
		(start 148.710275 93.375)
		(mid 148.680986 93.304289)
		(end 148.610275 93.275)
		(width 0.1)
		(layer "In2.Cu")
		(net 207)
	)
	(arc
		(start 148.275 93.675)
		(mid 148.204289 93.645711)
		(end 148.175 93.575)
		(width 0.1)
		(layer "In2.Cu")
		(net 207)
	)
	(arc
		(start 148.610275 93.475)
		(mid 148.680986 93.445711)
		(end 148.710275 93.375)
		(width 0.1)
		(layer "In2.Cu")
		(net 207)
	)
	(arc
		(start 148.175 94.375)
		(mid 148.204289 94.304289)
		(end 148.275 94.275)
		(width 0.1)
		(layer "In2.Cu")
		(net 207)
	)
	(arc
		(start 148.275 93.275)
		(mid 148.204289 93.245711)
		(end 148.175 93.175)
		(width 0.1)
		(layer "In2.Cu")
		(net 207)
	)
	(arc
		(start 148.175 93.575)
		(mid 148.204289 93.504289)
		(end 148.275 93.475)
		(width 0.1)
		(layer "In2.Cu")
		(net 207)
	)
	(arc
		(start 148.610275 93.875)
		(mid 148.680986 93.845711)
		(end 148.710275 93.775)
		(width 0.1)
		(layer "In2.Cu")
		(net 207)
	)
	(arc
		(start 148.710275 93.775)
		(mid 148.680986 93.704289)
		(end 148.610275 93.675)
		(width 0.1)
		(layer "In2.Cu")
		(net 207)
	)
	(arc
		(start 148.275 94.075)
		(mid 148.204289 94.045711)
		(end 148.175 93.975)
		(width 0.1)
		(layer "In2.Cu")
		(net 207)
	)
	(arc
		(start 148.175 93.975)
		(mid 148.204289 93.904289)
		(end 148.275 93.875)
		(width 0.1)
		(layer "In2.Cu")
		(net 207)
	)
	(segment
		(start 147.375 92.3)
		(end 147.475 92.3)
		(width 0.1)
		(layer "F.Cu")
		(net 208)
	)
	(segment
		(start 147.925 98.7)
		(end 147.925 96.825)
		(width 0.2)
		(layer "F.Cu")
		(net 208)
	)
	(segment
		(start 147.475 92.3)
		(end 147.775 92.6)
		(width 0.1)
		(layer "F.Cu")
		(net 208)
	)
	(via
		(at 147.925 96.825)
		(size 0.4)
		(drill 0.15)
		(layers "F.Cu" "B.Cu")
		(net 208)
	)
	(via
		(at 147.775 92.6)
		(size 0.4)
		(drill 0.15)
		(layers "F.Cu" "B.Cu")
		(net 208)
	)
	(segment
		(start 147.925 96.25)
		(end 147.775 96.1)
		(width 0.1)
		(layer "In2.Cu")
		(net 208)
	)
	(segment
		(start 147.339646 95.225)
		(end 147.675 95.225)
		(width 0.1)
		(layer "In2.Cu")
		(net 208)
	)
	(segment
		(start 147.675 95.425)
		(end 147.339646 95.425)
		(width 0.1)
		(layer "In2.Cu")
		(net 208)
	)
	(segment
		(start 147.675 95.825)
		(end 147.339646 95.825)
		(width 0.1)
		(layer "In2.Cu")
		(net 208)
	)
	(segment
		(start 147.675 93.325)
		(end 147.475 93.325)
		(width 0.1)
		(layer "In2.Cu")
		(net 208)
	)
	(segment
		(start 147.775 94.725)
		(end 147.775 94.675)
		(width 0.1)
		(layer "In2.Cu")
		(net 208)
	)
	(segment
		(start 147.775 94.675)
		(end 147.775 93.825)
		(width 0.1)
		(layer "In2.Cu")
		(net 208)
	)
	(segment
		(start 147.775 93.025)
		(end 147.775 92.6)
		(width 0.1)
		(layer "In2.Cu")
		(net 208)
	)
	(segment
		(start 147.925 96.825)
		(end 147.925 96.25)
		(width 0.1)
		(layer "In2.Cu")
		(net 208)
	)
	(segment
		(start 147.775 96.1)
		(end 147.775 95.925)
		(width 0.1)
		(layer "In2.Cu")
		(net 208)
	)
	(segment
		(start 147.675 93.725)
		(end 147.525 93.725)
		(width 0.1)
		(layer "In2.Cu")
		(net 208)
	)
	(segment
		(start 147.475 93.125)
		(end 147.675 93.125)
		(width 0.1)
		(layer "In2.Cu")
		(net 208)
	)
	(segment
		(start 147.339646 95.625)
		(end 147.675 95.625)
		(width 0.1)
		(layer "In2.Cu")
		(net 208)
	)
	(segment
		(start 147.525 93.525)
		(end 147.675 93.525)
		(width 0.1)
		(layer "In2.Cu")
		(net 208)
	)
	(segment
		(start 147.489646 94.825)
		(end 147.675 94.825)
		(width 0.1)
		(layer "In2.Cu")
		(net 208)
	)
	(segment
		(start 147.675 95.025)
		(end 147.489646 95.025)
		(width 0.1)
		(layer "In2.Cu")
		(net 208)
	)
	(arc
		(start 147.425 93.625)
		(mid 147.454289 93.554289)
		(end 147.525 93.525)
		(width 0.1)
		(layer "In2.Cu")
		(net 208)
	)
	(arc
		(start 147.675 95.625)
		(mid 147.745711 95.595711)
		(end 147.775 95.525)
		(width 0.1)
		(layer "In2.Cu")
		(net 208)
	)
	(arc
		(start 147.675 94.825)
		(mid 147.745711 94.795711)
		(end 147.775 94.725)
		(width 0.1)
		(layer "In2.Cu")
		(net 208)
	)
	(arc
		(start 147.775 95.525)
		(mid 147.745711 95.454289)
		(end 147.675 95.425)
		(width 0.1)
		(layer "In2.Cu")
		(net 208)
	)
	(arc
		(start 147.675 93.125)
		(mid 147.745711 93.095711)
		(end 147.775 93.025)
		(width 0.1)
		(layer "In2.Cu")
		(net 208)
	)
	(arc
		(start 147.475 93.325)
		(mid 147.404289 93.295711)
		(end 147.375 93.225)
		(width 0.1)
		(layer "In2.Cu")
		(net 208)
	)
	(arc
		(start 147.239646 95.725)
		(mid 147.268935 95.654289)
		(end 147.339646 95.625)
		(width 0.1)
		(layer "In2.Cu")
		(net 208)
	)
	(arc
		(start 147.775 95.125)
		(mid 147.745711 95.054289)
		(end 147.675 95.025)
		(width 0.1)
		(layer "In2.Cu")
		(net 208)
	)
	(arc
		(start 147.675 95.225)
		(mid 147.745711 95.195711)
		(end 147.775 95.125)
		(width 0.1)
		(layer "In2.Cu")
		(net 208)
	)
	(arc
		(start 147.389646 94.925)
		(mid 147.418935 94.854289)
		(end 147.489646 94.825)
		(width 0.1)
		(layer "In2.Cu")
		(net 208)
	)
	(arc
		(start 147.775 93.825)
		(mid 147.745711 93.754289)
		(end 147.675 93.725)
		(width 0.1)
		(layer "In2.Cu")
		(net 208)
	)
	(arc
		(start 147.775 93.425)
		(mid 147.745711 93.354289)
		(end 147.675 93.325)
		(width 0.1)
		(layer "In2.Cu")
		(net 208)
	)
	(arc
		(start 147.239646 95.325)
		(mid 147.268935 95.254289)
		(end 147.339646 95.225)
		(width 0.1)
		(layer "In2.Cu")
		(net 208)
	)
	(arc
		(start 147.339646 95.425)
		(mid 147.268935 95.395711)
		(end 147.239646 95.325)
		(width 0.1)
		(layer "In2.Cu")
		(net 208)
	)
	(arc
		(start 147.525 93.725)
		(mid 147.454289 93.695711)
		(end 147.425 93.625)
		(width 0.1)
		(layer "In2.Cu")
		(net 208)
	)
	(arc
		(start 147.675 93.525)
		(mid 147.745711 93.495711)
		(end 147.775 93.425)
		(width 0.1)
		(layer "In2.Cu")
		(net 208)
	)
	(arc
		(start 147.775 95.925)
		(mid 147.745711 95.854289)
		(end 147.675 95.825)
		(width 0.1)
		(layer "In2.Cu")
		(net 208)
	)
	(arc
		(start 147.375 93.225)
		(mid 147.404289 93.154289)
		(end 147.475 93.125)
		(width 0.1)
		(layer "In2.Cu")
		(net 208)
	)
	(arc
		(start 147.339646 95.825)
		(mid 147.268935 95.795711)
		(end 147.239646 95.725)
		(width 0.1)
		(layer "In2.Cu")
		(net 208)
	)
	(arc
		(start 147.489646 95.025)
		(mid 147.418935 94.995711)
		(end 147.389646 94.925)
		(width 0.1)
		(layer "In2.Cu")
		(net 208)
	)
	(segment
		(start 146.608876 91)
		(end 146.943241 90.665635)
		(width 0.1)
		(layer "F.Cu")
		(net 209)
	)
	(segment
		(start 146.925 98.7)
		(end 146.925 96.825)
		(width 0.2)
		(layer "F.Cu")
		(net 209)
	)
	(via
		(at 146.943241 90.665635)
		(size 0.4)
		(drill 0.15)
		(layers "F.Cu" "B.Cu")
		(net 209)
	)
	(via
		(at 146.925 96.825)
		(size 0.4)
		(drill 0.15)
		(layers "F.Cu" "B.Cu")
		(net 209)
	)
	(segment
		(start 146.72501 93.88001)
		(end 146.72501 91.19999)
		(width 0.1)
		(layer "In2.Cu")
		(net 209)
	)
	(segment
		(start 147.097206 94.55501)
		(end 146.85001 94.55501)
		(width 0.1)
		(layer "In2.Cu")
		(net 209)
	)
	(segment
		(start 146.72501 93.93001)
		(end 146.72501 93.88001)
		(width 0.1)
		(layer "In2.Cu")
		(net 209)
	)
	(segment
		(start 146.72501 91.19999)
		(end 146.943241 90.981759)
		(width 0.1)
		(layer "In2.Cu")
		(net 209)
	)
	(segment
		(start 146.85001 94.80501)
		(end 147.097206 94.80501)
		(width 0.1)
		(layer "In2.Cu")
		(net 209)
	)
	(segment
		(start 146.925 96.825)
		(end 146.925 95.999995)
		(width 0.1)
		(layer "In2.Cu")
		(net 209)
	)
	(segment
		(start 146.85001 94.30501)
		(end 147.097206 94.30501)
		(width 0.1)
		(layer "In2.Cu")
		(net 209)
	)
	(segment
		(start 146.925 95.999995)
		(end 146.72501 95.800005)
		(width 0.1)
		(layer "In2.Cu")
		(net 209)
	)
	(segment
		(start 147.097206 94.05501)
		(end 146.85001 94.05501)
		(width 0.1)
		(layer "In2.Cu")
		(net 209)
	)
	(segment
		(start 146.943241 90.981759)
		(end 146.943241 90.665635)
		(width 0.1)
		(layer "In2.Cu")
		(net 209)
	)
	(segment
		(start 146.72501 95.800005)
		(end 146.72501 94.93001)
		(width 0.1)
		(layer "In2.Cu")
		(net 209)
	)
	(arc
		(start 146.85001 94.05501)
		(mid 146.761622 94.018398)
		(end 146.72501 93.93001)
		(width 0.1)
		(layer "In2.Cu")
		(net 209)
	)
	(arc
		(start 147.222206 94.18001)
		(mid 147.185594 94.091622)
		(end 147.097206 94.05501)
		(width 0.1)
		(layer "In2.Cu")
		(net 209)
	)
	(arc
		(start 147.097206 94.30501)
		(mid 147.185594 94.268398)
		(end 147.222206 94.18001)
		(width 0.1)
		(layer "In2.Cu")
		(net 209)
	)
	(arc
		(start 146.72501 94.43001)
		(mid 146.761622 94.341622)
		(end 146.85001 94.30501)
		(width 0.1)
		(layer "In2.Cu")
		(net 209)
	)
	(arc
		(start 147.097206 94.80501)
		(mid 147.185594 94.768398)
		(end 147.222206 94.68001)
		(width 0.1)
		(layer "In2.Cu")
		(net 209)
	)
	(arc
		(start 146.85001 94.55501)
		(mid 146.761622 94.518398)
		(end 146.72501 94.43001)
		(width 0.1)
		(layer "In2.Cu")
		(net 209)
	)
	(arc
		(start 146.72501 94.93001)
		(mid 146.761622 94.841622)
		(end 146.85001 94.80501)
		(width 0.1)
		(layer "In2.Cu")
		(net 209)
	)
	(arc
		(start 147.222206 94.68001)
		(mid 147.185594 94.591622)
		(end 147.097206 94.55501)
		(width 0.1)
		(layer "In2.Cu")
		(net 209)
	)
	(segment
		(start 146.525 90.35)
		(end 146.17502 90.69998)
		(width 0.1)
		(layer "F.Cu")
		(net 210)
	)
	(segment
		(start 146.575 90.35)
		(end 146.525 90.35)
		(width 0.1)
		(layer "F.Cu")
		(net 210)
	)
	(segment
		(start 146.425 98.7)
		(end 146.425 96.37501)
		(width 0.2)
		(layer "F.Cu")
		(net 210)
	)
	(via
		(at 146.175 90.69998)
		(size 0.4)
		(drill 0.15)
		(layers "F.Cu" "B.Cu")
		(net 210)
	)
	(via
		(at 146.425 96.325)
		(size 0.4)
		(drill 0.15)
		(layers "F.Cu" "B.Cu")
		(net 210)
	)
	(segment
		(start 146.282917 93.485)
		(end 146.4 93.485)
		(width 0.1)
		(layer "In2.Cu")
		(net 210)
	)
	(segment
		(start 146.425 96.325)
		(end 146.425 95.921437)
		(width 0.1)
		(layer "In2.Cu")
		(net 210)
	)
	(segment
		(start 146.525 91.05)
		(end 146.175 90.7)
		(width 0.1)
		(layer "In2.Cu")
		(net 210)
	)
	(segment
		(start 146.525 95.821437)
		(end 146.525 94.86)
		(width 0.1)
		(layer "In2.Cu")
		(net 210)
	)
	(segment
		(start 146.4 94.735)
		(end 146.282917 94.735)
		(width 0.1)
		(layer "In2.Cu")
		(net 210)
	)
	(segment
		(start 146.4 94.235)
		(end 146.282917 94.235)
		(width 0.1)
		(layer "In2.Cu")
		(net 210)
	)
	(segment
		(start 146.525 93.31)
		(end 146.525 91.05)
		(width 0.1)
		(layer "In2.Cu")
		(net 210)
	)
	(segment
		(start 146.4 93.735)
		(end 146.282917 93.735)
		(width 0.1)
		(layer "In2.Cu")
		(net 210)
	)
	(segment
		(start 146.525 93.36)
		(end 146.525 93.31)
		(width 0.1)
		(layer "In2.Cu")
		(net 210)
	)
	(segment
		(start 146.282917 93.985)
		(end 146.4 93.985)
		(width 0.1)
		(layer "In2.Cu")
		(net 210)
	)
	(segment
		(start 146.282917 94.485)
		(end 146.4 94.485)
		(width 0.1)
		(layer "In2.Cu")
		(net 210)
	)
	(segment
		(start 146.175 90.7)
		(end 146.175 90.69998)
		(width 0.1)
		(layer "In2.Cu")
		(net 210)
	)
	(segment
		(start 146.425 95.921437)
		(end 146.525 95.821437)
		(width 0.1)
		(layer "In2.Cu")
		(net 210)
	)
	(arc
		(start 146.525 94.86)
		(mid 146.488388 94.771612)
		(end 146.4 94.735)
		(width 0.1)
		(layer "In2.Cu")
		(net 210)
	)
	(arc
		(start 146.525 93.86)
		(mid 146.488388 93.771612)
		(end 146.4 93.735)
		(width 0.1)
		(layer "In2.Cu")
		(net 210)
	)
	(arc
		(start 146.157917 94.11)
		(mid 146.194529 94.021612)
		(end 146.282917 93.985)
		(width 0.1)
		(layer "In2.Cu")
		(net 210)
	)
	(arc
		(start 146.282917 94.735)
		(mid 146.194529 94.698388)
		(end 146.157917 94.61)
		(width 0.1)
		(layer "In2.Cu")
		(net 210)
	)
	(arc
		(start 146.157917 93.61)
		(mid 146.194529 93.521612)
		(end 146.282917 93.485)
		(width 0.1)
		(layer "In2.Cu")
		(net 210)
	)
	(arc
		(start 146.525 94.36)
		(mid 146.488388 94.271612)
		(end 146.4 94.235)
		(width 0.1)
		(layer "In2.Cu")
		(net 210)
	)
	(arc
		(start 146.157917 94.61)
		(mid 146.194529 94.521612)
		(end 146.282917 94.485)
		(width 0.1)
		(layer "In2.Cu")
		(net 210)
	)
	(arc
		(start 146.4 94.485)
		(mid 146.488388 94.448388)
		(end 146.525 94.36)
		(width 0.1)
		(layer "In2.Cu")
		(net 210)
	)
	(arc
		(start 146.4 93.485)
		(mid 146.488388 93.448388)
		(end 146.525 93.36)
		(width 0.1)
		(layer "In2.Cu")
		(net 210)
	)
	(arc
		(start 146.282917 93.735)
		(mid 146.194529 93.698388)
		(end 146.157917 93.61)
		(width 0.1)
		(layer "In2.Cu")
		(net 210)
	)
	(arc
		(start 146.4 93.985)
		(mid 146.488388 93.948388)
		(end 146.525 93.86)
		(width 0.1)
		(layer "In2.Cu")
		(net 210)
	)
	(arc
		(start 146.282917 94.235)
		(mid 146.194529 94.198388)
		(end 146.157917 94.11)
		(width 0.1)
		(layer "In2.Cu")
		(net 210)
	)
	(segment
		(start 145.925 98.7)
		(end 145.925 96.825)
		(width 0.2)
		(layer "F.Cu")
		(net 211)
	)
	(segment
		(start 146.575 91.65)
		(end 146.525 91.65)
		(width 0.1)
		(layer "F.Cu")
		(net 211)
	)
	(segment
		(start 146.525 91.65)
		(end 146.17502 91.99998)
		(width 0.1)
		(layer "F.Cu")
		(net 211)
	)
	(via
		(at 146.175 91.99998)
		(size 0.4)
		(drill 0.15)
		(layers "F.Cu" "B.Cu")
		(net 211)
	)
	(via
		(at 145.925 96.825)
		(size 0.4)
		(drill 0.15)
		(layers "F.Cu" "B.Cu")
		(net 211)
	)
	(segment
		(start 145.925 94.574635)
		(end 145.925 92.96)
		(width 0.1)
		(layer "In2.Cu")
		(net 211)
	)
	(segment
		(start 145.775 92.81)
		(end 145.775 92.39998)
		(width 0.1)
		(layer "In2.Cu")
		(net 211)
	)
	(segment
		(start 145.775 92.39998)
		(end 146.175 91.99998)
		(width 0.1)
		(layer "In2.Cu")
		(net 211)
	)
	(segment
		(start 145.925 94.825)
		(end 145.925 94.574635)
		(width 0.1)
		(layer "In2.Cu")
		(net 211)
	)
	(segment
		(start 145.925 95.125)
		(end 145.736768 95.125)
		(width 0.1)
		(layer "In2.Cu")
		(net 211)
	)
	(segment
		(start 146.213232 95.525)
		(end 145.925 95.525)
		(width 0.1)
		(layer "In2.Cu")
		(net 211)
	)
	(segment
		(start 145.925 92.96)
		(end 145.775 92.81)
		(width 0.1)
		(layer "In2.Cu")
		(net 211)
	)
	(segment
		(start 145.925 95.525)
		(end 145.736768 95.525)
		(width 0.1)
		(layer "In2.Cu")
		(net 211)
	)
	(segment
		(start 145.736768 95.725)
		(end 145.825 95.725)
		(width 0.1)
		(layer "In2.Cu")
		(net 211)
	)
	(segment
		(start 145.825 95.925)
		(end 145.736768 95.925)
		(width 0.1)
		(layer "In2.Cu")
		(net 211)
	)
	(segment
		(start 145.736768 94.925)
		(end 145.825 94.925)
		(width 0.1)
		(layer "In2.Cu")
		(net 211)
	)
	(segment
		(start 145.825 95.725)
		(end 146.213232 95.725)
		(width 0.1)
		(layer "In2.Cu")
		(net 211)
	)
	(segment
		(start 145.925 96.825)
		(end 145.925 96.025)
		(width 0.1)
		(layer "In2.Cu")
		(net 211)
	)
	(segment
		(start 145.925 95.325)
		(end 146.213232 95.325)
		(width 0.1)
		(layer "In2.Cu")
		(net 211)
	)
	(segment
		(start 145.736768 95.325)
		(end 145.925 95.325)
		(width 0.1)
		(layer "In2.Cu")
		(net 211)
	)
	(segment
		(start 146.213232 95.125)
		(end 145.925 95.125)
		(width 0.1)
		(layer "In2.Cu")
		(net 211)
	)
	(arc
		(start 146.313232 95.225)
		(mid 146.283943 95.154289)
		(end 146.213232 95.125)
		(width 0.1)
		(layer "In2.Cu")
		(net 211)
	)
	(arc
		(start 146.313232 95.625)
		(mid 146.283943 95.554289)
		(end 146.213232 95.525)
		(width 0.1)
		(layer "In2.Cu")
		(net 211)
	)
	(arc
		(start 145.736768 95.925)
		(mid 145.666057 95.895711)
		(end 145.636768 95.825)
		(width 0.1)
		(layer "In2.Cu")
		(net 211)
	)
	(arc
		(start 146.213232 95.725)
		(mid 146.283943 95.695711)
		(end 146.313232 95.625)
		(width 0.1)
		(layer "In2.Cu")
		(net 211)
	)
	(arc
		(start 145.825 94.925)
		(mid 145.895711 94.895711)
		(end 145.925 94.825)
		(width 0.1)
		(layer "In2.Cu")
		(net 211)
	)
	(arc
		(start 145.636768 95.825)
		(mid 145.666057 95.754289)
		(end 145.736768 95.725)
		(width 0.1)
		(layer "In2.Cu")
		(net 211)
	)
	(arc
		(start 146.213232 95.325)
		(mid 146.283943 95.295711)
		(end 146.313232 95.225)
		(width 0.1)
		(layer "In2.Cu")
		(net 211)
	)
	(arc
		(start 145.636768 95.425)
		(mid 145.666057 95.354289)
		(end 145.736768 95.325)
		(width 0.1)
		(layer "In2.Cu")
		(net 211)
	)
	(arc
		(start 145.736768 95.525)
		(mid 145.666057 95.495711)
		(end 145.636768 95.425)
		(width 0.1)
		(layer "In2.Cu")
		(net 211)
	)
	(arc
		(start 145.925 96.025)
		(mid 145.895711 95.954289)
		(end 145.825 95.925)
		(width 0.1)
		(layer "In2.Cu")
		(net 211)
	)
	(arc
		(start 145.636768 95.025)
		(mid 145.666057 94.954289)
		(end 145.736768 94.925)
		(width 0.1)
		(layer "In2.Cu")
		(net 211)
	)
	(arc
		(start 145.736768 95.125)
		(mid 145.666057 95.095711)
		(end 145.636768 95.025)
		(width 0.1)
		(layer "In2.Cu")
		(net 211)
	)
	(segment
		(start 145.725 92.3)
		(end 145.37502 92.64998)
		(width 0.1)
		(layer "F.Cu")
		(net 212)
	)
	(segment
		(start 145.775 92.3)
		(end 145.725 92.3)
		(width 0.1)
		(layer "F.Cu")
		(net 212)
	)
	(segment
		(start 145.37502 92.64998)
		(end 145.375 92.64998)
		(width 0.1)
		(layer "F.Cu")
		(net 212)
	)
	(segment
		(start 145.425 98.7)
		(end 145.425 96.325)
		(width 0.2)
		(layer "F.Cu")
		(net 212)
	)
	(via
		(at 145.375 92.64998)
		(size 0.4)
		(drill 0.15)
		(layers "F.Cu" "B.Cu")
		(net 212)
	)
	(via
		(at 145.425 96.325)
		(size 0.4)
		(drill 0.15)
		(layers "F.Cu" "B.Cu")
		(net 212)
	)
	(segment
		(start 145.614779 93.98)
		(end 145.325 93.98)
		(width 0.1)
		(layer "In2.Cu")
		(net 212)
	)
	(segment
		(start 145.614779 93.58)
		(end 145.325 93.58)
		(width 0.1)
		(layer "In2.Cu")
		(net 212)
	)
	(segment
		(start 145.325 92.95)
		(end 145.375 92.9)
		(width 0.1)
		(layer "In2.Cu")
		(net 212)
	)
	(segment
		(start 145.614779 93.18)
		(end 145.425 93.18)
		(width 0.1)
		(layer "In2.Cu")
		(net 212)
	)
	(segment
		(start 145.23011 93.78)
		(end 145.325 93.78)
		(width 0.1)
		(layer "In2.Cu")
		(net 212)
	)
	(segment
		(start 145.325 93.38)
		(end 145.614779 93.38)
		(width 0.1)
		(layer "In2.Cu")
		(net 212)
	)
	(segment
		(start 145.135221 94.285111)
		(end 145.135221 94.274889)
		(width 0.1)
		(layer "In2.Cu")
		(net 212)
	)
	(segment
		(start 145.325 93.78)
		(end 145.614779 93.78)
		(width 0.1)
		(layer "In2.Cu")
		(net 212)
	)
	(segment
		(start 145.425 94.38)
		(end 145.23011 94.38)
		(width 0.1)
		(layer "In2.Cu")
		(net 212)
	)
	(segment
		(start 145.135221 93.885111)
		(end 145.135221 93.874889)
		(width 0.1)
		(layer "In2.Cu")
		(net 212)
	)
	(segment
		(start 145.325 93.08)
		(end 145.325 92.95)
		(width 0.1)
		(layer "In2.Cu")
		(net 212)
	)
	(segment
		(start 145.23011 94.18)
		(end 145.325 94.18)
		(width 0.1)
		(layer "In2.Cu")
		(net 212)
	)
	(segment
		(start 145.425 94.91)
		(end 145.325 94.81)
		(width 0.1)
		(layer "In2.Cu")
		(net 212)
	)
	(segment
		(start 145.325 94.18)
		(end 145.614779 94.18)
		(width 0.1)
		(layer "In2.Cu")
		(net 212)
	)
	(segment
		(start 145.425 96.325)
		(end 145.425 94.91)
		(width 0.1)
		(layer "In2.Cu")
		(net 212)
	)
	(segment
		(start 145.425 94.58)
		(end 145.614779 94.58)
		(width 0.1)
		(layer "In2.Cu")
		(net 212)
	)
	(segment
		(start 145.375 92.9)
		(end 145.375 92.64998)
		(width 0.1)
		(layer "In2.Cu")
		(net 212)
	)
	(segment
		(start 145.23011 93.38)
		(end 145.325 93.38)
		(width 0.1)
		(layer "In2.Cu")
		(net 212)
	)
	(segment
		(start 145.325 93.98)
		(end 145.23011 93.98)
		(width 0.1)
		(layer "In2.Cu")
		(net 212)
	)
	(segment
		(start 145.325 94.81)
		(end 145.325 94.68)
		(width 0.1)
		(layer "In2.Cu")
		(net 212)
	)
	(segment
		(start 145.325 93.58)
		(end 145.23011 93.58)
		(width 0.1)
		(layer "In2.Cu")
		(net 212)
	)
	(segment
		(start 145.135221 93.485111)
		(end 145.135221 93.474889)
		(width 0.1)
		(layer "In2.Cu")
		(net 212)
	)
	(segment
		(start 145.614779 94.38)
		(end 145.425 94.38)
		(width 0.1)
		(layer "In2.Cu")
		(net 212)
	)
	(arc
		(start 145.23011 93.98)
		(mid 145.163013 93.952208)
		(end 145.135221 93.885111)
		(width 0.1)
		(layer "In2.Cu")
		(net 212)
	)
	(arc
		(start 145.714779 94.48)
		(mid 145.68549 94.409289)
		(end 145.614779 94.38)
		(width 0.1)
		(layer "In2.Cu")
		(net 212)
	)
	(arc
		(start 145.135221 94.274889)
		(mid 145.163013 94.207792)
		(end 145.23011 94.18)
		(width 0.1)
		(layer "In2.Cu")
		(net 212)
	)
	(arc
		(start 145.135221 93.474889)
		(mid 145.163013 93.407792)
		(end 145.23011 93.38)
		(width 0.1)
		(layer "In2.Cu")
		(net 212)
	)
	(arc
		(start 145.425 93.18)
		(mid 145.354289 93.150711)
		(end 145.325 93.08)
		(width 0.1)
		(layer "In2.Cu")
		(net 212)
	)
	(arc
		(start 145.23011 94.38)
		(mid 145.163013 94.352208)
		(end 145.135221 94.285111)
		(width 0.1)
		(layer "In2.Cu")
		(net 212)
	)
	(arc
		(start 145.325 94.68)
		(mid 145.354289 94.609289)
		(end 145.425 94.58)
		(width 0.1)
		(layer "In2.Cu")
		(net 212)
	)
	(arc
		(start 145.614779 93.78)
		(mid 145.68549 93.750711)
		(end 145.714779 93.68)
		(width 0.1)
		(layer "In2.Cu")
		(net 212)
	)
	(arc
		(start 145.614779 94.18)
		(mid 145.68549 94.150711)
		(end 145.714779 94.08)
		(width 0.1)
		(layer "In2.Cu")
		(net 212)
	)
	(arc
		(start 145.714779 94.08)
		(mid 145.68549 94.009289)
		(end 145.614779 93.98)
		(width 0.1)
		(layer "In2.Cu")
		(net 212)
	)
	(arc
		(start 145.135221 93.874889)
		(mid 145.163013 93.807792)
		(end 145.23011 93.78)
		(width 0.1)
		(layer "In2.Cu")
		(net 212)
	)
	(arc
		(start 145.23011 93.58)
		(mid 145.163013 93.552208)
		(end 145.135221 93.485111)
		(width 0.1)
		(layer "In2.Cu")
		(net 212)
	)
	(arc
		(start 145.714779 93.28)
		(mid 145.68549 93.209289)
		(end 145.614779 93.18)
		(width 0.1)
		(layer "In2.Cu")
		(net 212)
	)
	(arc
		(start 145.614779 93.38)
		(mid 145.68549 93.350711)
		(end 145.714779 93.28)
		(width 0.1)
		(layer "In2.Cu")
		(net 212)
	)
	(arc
		(start 145.714779 93.68)
		(mid 145.68549 93.609289)
		(end 145.614779 93.58)
		(width 0.1)
		(layer "In2.Cu")
		(net 212)
	)
	(arc
		(start 145.614779 94.58)
		(mid 145.68549 94.550711)
		(end 145.714779 94.48)
		(width 0.1)
		(layer "In2.Cu")
		(net 212)
	)
	(segment
		(start 144.925 98.7)
		(end 144.925 96.825)
		(width 0.2)
		(layer "F.Cu")
		(net 213)
	)
	(segment
		(start 145.725 91.7)
		(end 145.37502 92.04998)
		(width 0.1)
		(layer "F.Cu")
		(net 213)
	)
	(segment
		(start 145.775 91.7)
		(end 145.725 91.7)
		(width 0.1)
		(layer "F.Cu")
		(net 213)
	)
	(via
		(at 144.925 96.825)
		(size 0.4)
		(drill 0.15)
		(layers "F.Cu" "B.Cu")
		(net 213)
	)
	(via
		(at 145.375 92.04998)
		(size 0.4)
		(drill 0.15)
		(layers "F.Cu" "B.Cu")
		(net 213)
	)
	(segment
		(start 144.925 92.49998)
		(end 145.375 92.04998)
		(width 0.1)
		(layer "In2.Cu")
		(net 213)
	)
	(segment
		(start 144.925 94.98)
		(end 144.925 94.643181)
		(width 0.1)
		(layer "In2.Cu")
		(net 213)
	)
	(segment
		(start 145.06025 95.855)
		(end 144.925 95.855)
		(width 0.1)
		(layer "In2.Cu")
		(net 213)
	)
	(segment
		(start 144.63975 95.605)
		(end 144.925 95.605)
		(width 0.1)
		(layer "In2.Cu")
		(net 213)
	)
	(segment
		(start 144.925 95.355)
		(end 144.63975 95.355)
		(width 0.1)
		(layer "In2.Cu")
		(net 213)
	)
	(segment
		(start 144.63975 95.105)
		(end 144.8 95.105)
		(width 0.1)
		(layer "In2.Cu")
		(net 213)
	)
	(segment
		(start 144.925 95.855)
		(end 144.63975 95.855)
		(width 0.1)
		(layer "In2.Cu")
		(net 213)
	)
	(segment
		(start 144.8 96.105)
		(end 145.06025 96.105)
		(width 0.1)
		(layer "In2.Cu")
		(net 213)
	)
	(segment
		(start 144.8 96.355)
		(end 144.63975 96.355)
		(width 0.1)
		(layer "In2.Cu")
		(net 213)
	)
	(segment
		(start 145.06025 95.355)
		(end 144.925 95.355)
		(width 0.1)
		(layer "In2.Cu")
		(net 213)
	)
	(segment
		(start 144.925 96.825)
		(end 144.925 96.48)
		(width 0.1)
		(layer "In2.Cu")
		(net 213)
	)
	(segment
		(start 144.925 95.605)
		(end 145.06025 95.605)
		(width 0.1)
		(layer "In2.Cu")
		(net 213)
	)
	(segment
		(start 144.925 94.643181)
		(end 144.925 92.49998)
		(width 0.1)
		(layer "In2.Cu")
		(net 213)
	)
	(segment
		(start 144.63975 96.105)
		(end 144.8 96.105)
		(width 0.1)
		(layer "In2.Cu")
		(net 213)
	)
	(arc
		(start 145.06025 95.605)
		(mid 145.148638 95.568388)
		(end 145.18525 95.48)
		(width 0.1)
		(layer "In2.Cu")
		(net 213)
	)
	(arc
		(start 144.63975 95.855)
		(mid 144.551362 95.818388)
		(end 144.51475 95.73)
		(width 0.1)
		(layer "In2.Cu")
		(net 213)
	)
	(arc
		(start 144.63975 95.355)
		(mid 144.551362 95.318388)
		(end 144.51475 95.23)
		(width 0.1)
		(layer "In2.Cu")
		(net 213)
	)
	(arc
		(start 145.18525 95.48)
		(mid 145.148638 95.391612)
		(end 145.06025 95.355)
		(width 0.1)
		(layer "In2.Cu")
		(net 213)
	)
	(arc
		(start 144.51475 95.73)
		(mid 144.551362 95.641612)
		(end 144.63975 95.605)
		(width 0.1)
		(layer "In2.Cu")
		(net 213)
	)
	(arc
		(start 144.925 96.48)
		(mid 144.888388 96.391612)
		(end 144.8 96.355)
		(width 0.1)
		(layer "In2.Cu")
		(net 213)
	)
	(arc
		(start 144.51475 95.23)
		(mid 144.551362 95.141612)
		(end 144.63975 95.105)
		(width 0.1)
		(layer "In2.Cu")
		(net 213)
	)
	(arc
		(start 144.63975 96.355)
		(mid 144.551362 96.318388)
		(end 144.51475 96.23)
		(width 0.1)
		(layer "In2.Cu")
		(net 213)
	)
	(arc
		(start 145.06025 96.105)
		(mid 145.148638 96.068388)
		(end 145.18525 95.98)
		(width 0.1)
		(layer "In2.Cu")
		(net 213)
	)
	(arc
		(start 144.8 95.105)
		(mid 144.888388 95.068388)
		(end 144.925 94.98)
		(width 0.1)
		(layer "In2.Cu")
		(net 213)
	)
	(arc
		(start 145.18525 95.98)
		(mid 145.148638 95.891612)
		(end 145.06025 95.855)
		(width 0.1)
		(layer "In2.Cu")
		(net 213)
	)
	(arc
		(start 144.51475 96.23)
		(mid 144.551362 96.141612)
		(end 144.63975 96.105)
		(width 0.1)
		(layer "In2.Cu")
		(net 213)
	)
	(segment
		(start 147.075 87.45)
		(end 147.375 87.75)
		(width 0.1)
		(layer "F.Cu")
		(net 214)
	)
	(segment
		(start 146.98628 87.45)
		(end 147.075 87.45)
		(width 0.1)
		(layer "F.Cu")
		(net 214)
	)
	(via
		(at 146.98628 87.45)
		(size 0.4)
		(drill 0.15)
		(layers "F.Cu" "B.Cu")
		(net 214)
	)
	(segment
		(start 144.175 97.225)
		(end 144.325 97.075)
		(width 0.1)
		(layer "B.Cu")
		(net 214)
	)
	(segment
		(start 147.324989 88.967153)
		(end 147.324989 87.788709)
		(width 0.1)
		(layer "B.Cu")
		(net 214)
	)
	(segment
		(start 146.792142 89.5)
		(end 147.324989 88.967153)
		(width 0.1)
		(layer "B.Cu")
		(net 214)
	)
	(segment
		(start 144.325 90.317157)
		(end 145.142157 89.5)
		(width 0.1)
		(layer "B.Cu")
		(net 214)
	)
	(segment
		(start 147.324989 87.788709)
		(end 146.98628 87.45)
		(width 0.1)
		(layer "B.Cu")
		(net 214)
	)
	(segment
		(start 144.325 97.075)
		(end 144.325 90.317157)
		(width 0.1)
		(layer "B.Cu")
		(net 214)
	)
	(segment
		(start 144.175 98.7)
		(end 144.175 97.225)
		(width 0.1)
		(layer "B.Cu")
		(net 214)
	)
	(segment
		(start 145.142157 89.5)
		(end 146.792142 89.5)
		(width 0.1)
		(layer "B.Cu")
		(net 214)
	)
	(segment
		(start 144.425 98.7)
		(end 144.425 96.1)
		(width 0.2)
		(layer "F.Cu")
		(net 215)
	)
	(segment
		(start 146.052512 90.072488)
		(end 145.775 90.35)
		(width 0.1)
		(layer "F.Cu")
		(net 215)
	)
	(segment
		(start 146.175 90.072488)
		(end 146.052512 90.072488)
		(width 0.1)
		(layer "F.Cu")
		(net 215)
	)
	(segment
		(start 144.425 96.1)
		(end 143.975 95.65)
		(width 0.2)
		(layer "F.Cu")
		(net 215)
	)
	(via
		(at 143.975 95.65)
		(size 0.4)
		(drill 0.15)
		(layers "F.Cu" "B.Cu")
		(net 215)
	)
	(via
		(at 146.175 90.072488)
		(size 0.4)
		(drill 0.15)
		(layers "F.Cu" "B.Cu")
		(net 215)
	)
	(segment
		(start 144.375 92.25)
		(end 144.375 93.45)
		(width 0.1)
		(layer "In2.Cu")
		(net 215)
	)
	(segment
		(start 144.375 93.45)
		(end 143.975 93.85)
		(width 0.1)
		(layer "In2.Cu")
		(net 215)
	)
	(segment
		(start 145.755 90.87)
		(end 144.375 92.25)
		(width 0.1)
		(layer "In2.Cu")
		(net 215)
	)
	(segment
		(start 143.975 93.85)
		(end 143.975 95.65)
		(width 0.1)
		(layer "In2.Cu")
		(net 215)
	)
	(segment
		(start 145.755 90.492488)
		(end 145.755 90.87)
		(width 0.1)
		(layer "In2.Cu")
		(net 215)
	)
	(segment
		(start 146.175 90.072488)
		(end 145.755 90.492488)
		(width 0.1)
		(layer "In2.Cu")
		(net 215)
	)
	(segment
		(start 147.78628 87.45)
		(end 147.875 87.45)
		(width 0.1)
		(layer "F.Cu")
		(net 216)
	)
	(segment
		(start 147.875 87.45)
		(end 148.175 87.75)
		(width 0.1)
		(layer "F.Cu")
		(net 216)
	)
	(via
		(at 147.78628 87.45)
		(size 0.4)
		(drill 0.15)
		(layers "F.Cu" "B.Cu")
		(net 216)
	)
	(segment
		(start 144.675 97.225)
		(end 144.525 97.075)
		(width 0.1)
		(layer "B.Cu")
		(net 216)
	)
	(segment
		(start 145.225 89.7)
		(end 146.875 89.7)
		(width 0.1)
		(layer "B.Cu")
		(net 216)
	)
	(segment
		(start 147.525 87.71128)
		(end 147.78628 87.45)
		(width 0.1)
		(layer "B.Cu")
		(net 216)
	)
	(segment
		(start 146.875 89.7)
		(end 147.525 89.05)
		(width 0.1)
		(layer "B.Cu")
		(net 216)
	)
	(segment
		(start 144.675 98.7)
		(end 144.675 97.225)
		(width 0.1)
		(layer "B.Cu")
		(net 216)
	)
	(segment
		(start 147.525 89.05)
		(end 147.525 87.71128)
		(width 0.1)
		(layer "B.Cu")
		(net 216)
	)
	(segment
		(start 144.525 97.075)
		(end 144.525 90.4)
		(width 0.1)
		(layer "B.Cu")
		(net 216)
	)
	(segment
		(start 144.525 90.4)
		(end 145.225 89.7)
		(width 0.1)
		(layer "B.Cu")
		(net 216)
	)
	(segment
		(start 145.775 89.7)
		(end 145.725 89.7)
		(width 0.1)
		(layer "F.Cu")
		(net 217)
	)
	(segment
		(start 145.725 89.7)
		(end 145.37502 90.04998)
		(width 0.1)
		(layer "F.Cu")
		(net 217)
	)
	(segment
		(start 143.925 98.7)
		(end 143.925 96.825)
		(width 0.2)
		(layer "F.Cu")
		(net 217)
	)
	(via
		(at 145.375 90.04998)
		(size 0.4)
		(drill 0.15)
		(layers "F.Cu" "B.Cu")
		(net 217)
	)
	(via
		(at 143.925 96.825)
		(size 0.4)
		(drill 0.15)
		(layers "F.Cu" "B.Cu")
		(net 217)
	)
	(segment
		(start 143.925 96.23)
		(end 143.925 96.825)
		(width 0.1)
		(layer "In2.Cu")
		(net 217)
	)
	(segment
		(start 145.375 90.04998)
		(end 143.4 92.02498)
		(width 0.1)
		(layer "In2.Cu")
		(net 217)
	)
	(segment
		(start 143.4 95.705)
		(end 143.925 96.23)
		(width 0.1)
		(layer "In2.Cu")
		(net 217)
	)
	(segment
		(start 143.4 92.02498)
		(end 143.4 95.705)
		(width 0.1)
		(layer "In2.Cu")
		(net 217)
	)
	(segment
		(start 147.11795 88.65705)
		(end 146.974979 88.65705)
		(width 0.1)
		(layer "F.Cu")
		(net 218)
	)
	(segment
		(start 147.375 88.4)
		(end 147.11795 88.65705)
		(width 0.1)
		(layer "F.Cu")
		(net 218)
	)
	(via
		(at 146.975 88.65705)
		(size 0.4)
		(drill 0.15)
		(layers "F.Cu" "B.Cu")
		(net 218)
	)
	(segment
		(start 143.5 94.975)
		(end 143.835479 94.975)
		(width 0.1)
		(layer "B.Cu")
		(net 218)
	)
	(segment
		(start 143.675 97.28)
		(end 143.475 97.08)
		(width 0.1)
		(layer "B.Cu")
		(net 218)
	)
	(segment
		(start 144.745 89.11)
		(end 145.885 89.11)
		(width 0.1)
		(layer "B.Cu")
		(net 218)
	)
	(segment
		(start 146.33795 88.65705)
		(end 146.974979 88.65705)
		(width 0.1)
		(layer "B.Cu")
		(net 218)
	)
	(segment
		(start 143.625 90.23)
		(end 144.745 89.11)
		(width 0.1)
		(layer "B.Cu")
		(net 218)
	)
	(segment
		(start 143.625 96.56)
		(end 143.625 95.35)
		(width 0.1)
		(layer "B.Cu")
		(net 218)
	)
	(segment
		(start 143.675 98.7)
		(end 143.675 97.28)
		(width 0.1)
		(layer "B.Cu")
		(net 218)
	)
	(segment
		(start 143.625 94.6)
		(end 143.625 94.480615)
		(width 0.1)
		(layer "B.Cu")
		(net 218)
	)
	(segment
		(start 143.625 94.480615)
		(end 143.625 90.23)
		(width 0.1)
		(layer "B.Cu")
		(net 218)
	)
	(segment
		(start 143.414521 94.975)
		(end 143.5 94.975)
		(width 0.1)
		(layer "B.Cu")
		(net 218)
	)
	(segment
		(start 143.475 97.08)
		(end 143.475 96.71)
		(width 0.1)
		(layer "B.Cu")
		(net 218)
	)
	(segment
		(start 145.885 89.11)
		(end 146.33795 88.65705)
		(width 0.1)
		(layer "B.Cu")
		(net 218)
	)
	(segment
		(start 143.5 95.225)
		(end 143.414521 95.225)
		(width 0.1)
		(layer "B.Cu")
		(net 218)
	)
	(segment
		(start 143.475 96.71)
		(end 143.625 96.56)
		(width 0.1)
		(layer "B.Cu")
		(net 218)
	)
	(segment
		(start 143.835479 94.725)
		(end 143.75 94.725)
		(width 0.1)
		(layer "B.Cu")
		(net 218)
	)
	(arc
		(start 143.75 94.725)
		(mid 143.661612 94.688388)
		(end 143.625 94.6)
		(width 0.1)
		(layer "B.Cu")
		(net 218)
	)
	(arc
		(start 143.289521 95.1)
		(mid 143.326133 95.011612)
		(end 143.414521 94.975)
		(width 0.1)
		(layer "B.Cu")
		(net 218)
	)
	(arc
		(start 143.960479 94.85)
		(mid 143.923867 94.761612)
		(end 143.835479 94.725)
		(width 0.1)
		(layer "B.Cu")
		(net 218)
	)
	(arc
		(start 143.835479 94.975)
		(mid 143.923867 94.938388)
		(end 143.960479 94.85)
		(width 0.1)
		(layer "B.Cu")
		(net 218)
	)
	(arc
		(start 143.414521 95.225)
		(mid 143.326133 95.188388)
		(end 143.289521 95.1)
		(width 0.1)
		(layer "B.Cu")
		(net 218)
	)
	(arc
		(start 143.625 95.35)
		(mid 143.588388 95.261612)
		(end 143.5 95.225)
		(width 0.1)
		(layer "B.Cu")
		(net 218)
	)
	(segment
		(start 146.575 88.4)
		(end 146.51128 88.4)
		(width 0.1)
		(layer "F.Cu")
		(net 219)
	)
	(segment
		(start 146.51128 88.4)
		(end 146.18628 88.075)
		(width 0.1)
		(layer "F.Cu")
		(net 219)
	)
	(via
		(at 146.18628 88.075)
		(size 0.4)
		(drill 0.15)
		(layers "F.Cu" "B.Cu")
		(net 219)
	)
	(segment
		(start 143.032713 93.75)
		(end 143.075 93.75)
		(width 0.1)
		(layer "B.Cu")
		(net 219)
	)
	(segment
		(start 142.874989 95.275011)
		(end 142.874989 94.949989)
		(width 0.1)
		(layer "B.Cu")
		(net 219)
	)
	(segment
		(start 143.175 98.7)
		(end 143.175 97.1)
		(width 0.1)
		(layer "B.Cu")
		(net 219)
	)
	(segment
		(start 144.435 88.75)
		(end 145.51128 88.75)
		(width 0.1)
		(layer "B.Cu")
		(net 219)
	)
	(segment
		(start 142.874989 94.949989)
		(end 143.2 94.624978)
		(width 0.1)
		(layer "B.Cu")
		(net 219)
	)
	(segment
		(start 143.15 95.925)
		(end 143.15 95.550022)
		(width 0.1)
		(layer "B.Cu")
		(net 219)
	)
	(segment
		(start 143.2 92)
		(end 142.874989 91.674989)
		(width 0.1)
		(layer "B.Cu")
		(net 219)
	)
	(segment
		(start 142.874989 96.200011)
		(end 143.15 95.925)
		(width 0.1)
		(layer "B.Cu")
		(net 219)
	)
	(segment
		(start 142.874989 91.674989)
		(end 142.874989 90.310011)
		(width 0.1)
		(layer "B.Cu")
		(net 219)
	)
	(segment
		(start 142.874989 90.310011)
		(end 144.435 88.75)
		(width 0.1)
		(layer "B.Cu")
		(net 219)
	)
	(segment
		(start 145.51128 88.75)
		(end 146.18628 88.075)
		(width 0.1)
		(layer "B.Cu")
		(net 219)
	)
	(segment
		(start 143.2 93.343238)
		(end 143.2 92)
		(width 0.1)
		(layer "B.Cu")
		(net 219)
	)
	(segment
		(start 143.2 94.624978)
		(end 143.2 94.125)
		(width 0.1)
		(layer "B.Cu")
		(net 219)
	)
	(segment
		(start 143.175 97.1)
		(end 142.874989 96.799989)
		(width 0.1)
		(layer "B.Cu")
		(net 219)
	)
	(segment
		(start 143.2 93.625)
		(end 143.2 93.343238)
		(width 0.1)
		(layer "B.Cu")
		(net 219)
	)
	(segment
		(start 142.874989 96.799989)
		(end 142.874989 96.200011)
		(width 0.1)
		(layer "B.Cu")
		(net 219)
	)
	(segment
		(start 143.15 95.550022)
		(end 142.874989 95.275011)
		(width 0.1)
		(layer "B.Cu")
		(net 219)
	)
	(segment
		(start 143.075 94)
		(end 143.032713 94)
		(width 0.1)
		(layer "B.Cu")
		(net 219)
	)
	(arc
		(start 142.907713 93.875)
		(mid 142.944325 93.786612)
		(end 143.032713 93.75)
		(width 0.1)
		(layer "B.Cu")
		(net 219)
	)
	(arc
		(start 143.075 93.75)
		(mid 143.163388 93.713388)
		(end 143.2 93.625)
		(width 0.1)
		(layer "B.Cu")
		(net 219)
	)
	(arc
		(start 143.2 94.125)
		(mid 143.163388 94.036612)
		(end 143.075 94)
		(width 0.1)
		(layer "B.Cu")
		(net 219)
	)
	(arc
		(start 143.032713 94)
		(mid 142.944325 93.963388)
		(end 142.907713 93.875)
		(width 0.1)
		(layer "B.Cu")
		(net 219)
	)
	(segment
		(start 145.775 88.4)
		(end 145.71128 88.4)
		(width 0.1)
		(layer "F.Cu")
		(net 220)
	)
	(segment
		(start 145.71128 88.4)
		(end 145.38628 88.075)
		(width 0.1)
		(layer "F.Cu")
		(net 220)
	)
	(via
		(at 145.38628 88.075)
		(size 0.4)
		(drill 0.15)
		(layers "F.Cu" "B.Cu")
		(net 220)
	)
	(segment
		(start 142.674978 95.875022)
		(end 142.674978 95.624978)
		(width 0.1)
		(layer "B.Cu")
		(net 220)
	)
	(segment
		(start 142.4 91.975)
		(end 142.4 90.1)
		(width 0.1)
		(layer "B.Cu")
		(net 220)
	)
	(segment
		(start 142.45 93.699978)
		(end 142.674978 93.475)
		(width 0.1)
		(layer "B.Cu")
		(net 220)
	)
	(segment
		(start 142.674978 93.475)
		(end 142.674978 93.249978)
		(width 0.1)
		(layer "B.Cu")
		(net 220)
	)
	(segment
		(start 142.499978 93.074978)
		(end 142.349978 93.074978)
		(width 0.1)
		(layer "B.Cu")
		(net 220)
	)
	(segment
		(start 142.349978 92.724978)
		(end 142.499978 92.724978)
		(width 0.1)
		(layer "B.Cu")
		(net 220)
	)
	(segment
		(start 142.4 90.1)
		(end 144.12 88.38)
		(width 0.1)
		(layer "B.Cu")
		(net 220)
	)
	(segment
		(start 142.675 97.35)
		(end 142.674978 97.349978)
		(width 0.1)
		(layer "B.Cu")
		(net 220)
	)
	(segment
		(start 142.674978 92.249978)
		(end 142.4 91.975)
		(width 0.1)
		(layer "B.Cu")
		(net 220)
	)
	(segment
		(start 142.674978 97.099978)
		(end 142.45 96.875)
		(width 0.1)
		(layer "B.Cu")
		(net 220)
	)
	(segment
		(start 142.674978 92.549978)
		(end 142.674978 92.539672)
		(width 0.1)
		(layer "B.Cu")
		(net 220)
	)
	(segment
		(start 144.12 88.38)
		(end 145.08128 88.38)
		(width 0.1)
		(layer "B.Cu")
		(net 220)
	)
	(segment
		(start 142.45 96.875)
		(end 142.45 96.1)
		(width 0.1)
		(layer "B.Cu")
		(net 220)
	)
	(segment
		(start 142.674978 95.624978)
		(end 142.45 95.4)
		(width 0.1)
		(layer "B.Cu")
		(net 220)
	)
	(segment
		(start 142.674978 92.539672)
		(end 142.674978 92.249978)
		(width 0.1)
		(layer "B.Cu")
		(net 220)
	)
	(segment
		(start 142.674978 97.349978)
		(end 142.674978 97.099978)
		(width 0.1)
		(layer "B.Cu")
		(net 220)
	)
	(segment
		(start 142.45 96.1)
		(end 142.674978 95.875022)
		(width 0.1)
		(layer "B.Cu")
		(net 220)
	)
	(segment
		(start 142.675 98.7)
		(end 142.675 97.35)
		(width 0.1)
		(layer "B.Cu")
		(net 220)
	)
	(segment
		(start 145.08128 88.38)
		(end 145.38628 88.075)
		(width 0.1)
		(layer "B.Cu")
		(net 220)
	)
	(segment
		(start 142.45 95.4)
		(end 142.45 93.699978)
		(width 0.1)
		(layer "B.Cu")
		(net 220)
	)
	(arc
		(start 142.674978 93.249978)
		(mid 142.623722 93.126234)
		(end 142.499978 93.074978)
		(width 0.1)
		(layer "B.Cu")
		(net 220)
	)
	(arc
		(start 142.174978 92.899978)
		(mid 142.226234 92.776234)
		(end 142.349978 92.724978)
		(width 0.1)
		(layer "B.Cu")
		(net 220)
	)
	(arc
		(start 142.499978 92.724978)
		(mid 142.623722 92.673722)
		(end 142.674978 92.549978)
		(width 0.1)
		(layer "B.Cu")
		(net 220)
	)
	(arc
		(start 142.349978 93.074978)
		(mid 142.226234 93.023722)
		(end 142.174978 92.899978)
		(width 0.1)
		(layer "B.Cu")
		(net 220)
	)
	(segment
		(start 145.775 87.75)
		(end 145.68628 87.75)
		(width 0.1)
		(layer "F.Cu")
		(net 221)
	)
	(segment
		(start 145.68628 87.75)
		(end 145.38628 87.45)
		(width 0.1)
		(layer "F.Cu")
		(net 221)
	)
	(via
		(at 145.38628 87.45)
		(size 0.4)
		(drill 0.15)
		(layers "F.Cu" "B.Cu")
		(net 221)
	)
	(segment
		(start 144.94628 87.89)
		(end 145.38628 87.45)
		(width 0.1)
		(layer "B.Cu")
		(net 221)
	)
	(segment
		(start 142.175 98.7)
		(end 142.175 96.05)
		(width 0.1)
		(layer "B.Cu")
		(net 221)
	)
	(segment
		(start 141.815 89.76)
		(end 143.685 87.89)
		(width 0.1)
		(layer "B.Cu")
		(net 221)
	)
	(segment
		(start 142.175 96.05)
		(end 141.815 95.69)
		(width 0.1)
		(layer "B.Cu")
		(net 221)
	)
	(segment
		(start 143.685 87.89)
		(end 144.94628 87.89)
		(width 0.1)
		(layer "B.Cu")
		(net 221)
	)
	(segment
		(start 141.815 95.69)
		(end 141.815 89.76)
		(width 0.1)
		(layer "B.Cu")
		(net 221)
	)
	(segment
		(start 151.375 83.85)
		(end 151.475 83.85)
		(width 0.1)
		(layer "F.Cu")
		(net 222)
	)
	(segment
		(start 151.475 83.85)
		(end 151.775 84.15)
		(width 0.1)
		(layer "F.Cu")
		(net 222)
	)
	(via
		(at 151.775 84.15)
		(size 0.4)
		(drill 0.15)
		(layers "F.Cu" "B.Cu")
		(net 222)
	)
	(segment
		(start 151.775 83.585)
		(end 151.775 84.15)
		(width 0.1)
		(layer "B.Cu")
		(net 222)
	)
	(segment
		(start 159.575 87.5)
		(end 158.86 87.5)
		(width 0.1)
		(layer "F.Cu")
		(net 229)
	)
	(via
		(at 159.575 87.5)
		(size 0.5)
		(drill 0.15)
		(layers "F.Cu" "B.Cu")
		(net 229)
	)
	(segment
		(start 151.325 96.719975)
		(end 151.075 96.469975)
		(width 0.1)
		(layer "B.Cu")
		(net 229)
	)
	(segment
		(start 151.325 97.05)
		(end 151.325 96.719975)
		(width 0.1)
		(layer "B.Cu")
		(net 229)
	)
	(segment
		(start 151.175 98.7)
		(end 151.175 97.2)
		(width 0.1)
		(layer "B.Cu")
		(net 229)
	)
	(segment
		(start 151.075 95)
		(end 151.375 94.7)
		(width 0.1)
		(layer "B.Cu")
		(net 229)
	)
	(segment
		(start 151.375 94.7)
		(end 151.375 87.775)
		(width 0.1)
		(layer "B.Cu")
		(net 229)
	)
	(segment
		(start 151.175 97.2)
		(end 151.325 97.05)
		(width 0.1)
		(layer "B.Cu")
		(net 229)
	)
	(segment
		(start 151.075 96.469975)
		(end 151.075 95)
		(width 0.1)
		(layer "B.Cu")
		(net 229)
	)
	(segment
		(start 151.375 87.775)
		(end 151.65 87.5)
		(width 0.1)
		(layer "B.Cu")
		(net 229)
	)
	(segment
		(start 151.65 87.5)
		(end 159.575 87.5)
		(width 0.1)
		(layer "B.Cu")
		(net 229)
	)
	(segment
		(start 142.529708 85.9)
		(end 142.679718 85.74999)
		(width 0.1)
		(layer "F.Cu")
		(net 230)
	)
	(segment
		(start 141.66 85.9)
		(end 142.529708 85.9)
		(width 0.1)
		(layer "F.Cu")
		(net 230)
	)
	(via
		(at 142.679718 85.74999)
		(size 0.4)
		(drill 0.15)
		(layers "F.Cu" "B.Cu")
		(net 230)
	)
	(via
		(at 149.455 85.6)
		(size 0.4)
		(drill 0.15)
		(layers "F.Cu" "B.Cu")
		(net 230)
	)
	(segment
		(start 150.524 93.851)
		(end 150.524 92.795955)
		(width 0.1)
		(layer "B.Cu")
		(net 230)
	)
	(segment
		(start 149.675 98.7)
		(end 149.675 97.25)
		(width 0.1)
		(layer "B.Cu")
		(net 230)
	)
	(segment
		(start 149.525 96.719975)
		(end 149.975 96.269975)
		(width 0.1)
		(layer "B.Cu")
		(net 230)
	)
	(segment
		(start 149.525 97.1)
		(end 149.525 96.719975)
		(width 0.1)
		(layer "B.Cu")
		(net 230)
	)
	(segment
		(start 149.675 97.25)
		(end 149.525 97.1)
		(width 0.1)
		(layer "B.Cu")
		(net 230)
	)
	(segment
		(start 149.455 85.6)
		(end 150.525001 86.670001)
		(width 0.1)
		(layer "B.Cu")
		(net 230)
	)
	(segment
		(start 149.975 96.269975)
		(end 149.975 94.4)
		(width 0.1)
		(layer "B.Cu")
		(net 230)
	)
	(segment
		(start 150.524 92.795955)
		(end 150.525 92.794955)
		(width 0.1)
		(layer "B.Cu")
		(net 230)
	)
	(segment
		(start 150.525 92.794955)
		(end 150.525001 86.67)
		(width 0.1)
		(layer "B.Cu")
		(net 230)
	)
	(segment
		(start 149.975 94.4)
		(end 150.524 93.851)
		(width 0.1)
		(layer "B.Cu")
		(net 230)
	)
	(segment
		(start 142.824999 85.85)
		(end 149.205 85.85)
		(width 0.1)
		(layer "In2.Cu")
		(net 230)
	)
	(segment
		(start 149.205 85.85)
		(end 149.455 85.6)
		(width 0.1)
		(layer "In2.Cu")
		(net 230)
	)
	(segment
		(start 127.975 82.625)
		(end 127.975 81.215)
		(width 0.2)
		(layer "F.Cu")
		(net 241)
	)
	(segment
		(start 130.15 82.625)
		(end 130.175 82.6)
		(width 0.2)
		(layer "F.Cu")
		(net 241)
	)
	(segment
		(start 130.175 82.6)
		(end 130.175 81.15)
		(width 0.2)
		(layer "F.Cu")
		(net 241)
	)
	(segment
		(start 127.975 81.215)
		(end 128.045 81.145)
		(width 0.2)
		(layer "F.Cu")
		(net 241)
	)
	(segment
		(start 127.975 82.625)
		(end 130.15 82.625)
		(width 0.2)
		(layer "F.Cu")
		(net 241)
	)
	(segment
		(start 125.105 85.31)
		(end 125.105 91.3)
		(width 0.2)
		(layer "F.Cu")
		(net 246)
	)
	(segment
		(start 128.025 92.1)
		(end 126.56 92.1)
		(width 0.2)
		(layer "F.Cu")
		(net 246)
	)
	(segment
		(start 127.14 83.275)
		(end 125.105 85.31)
		(width 0.2)
		(layer "F.Cu")
		(net 246)
	)
	(segment
		(start 129.375 92.53)
		(end 128.945 92.1)
		(width 0.2)
		(layer "F.Cu")
		(net 246)
	)
	(segment
		(start 127.975 83.275)
		(end 127.14 83.275)
		(width 0.2)
		(layer "F.Cu")
		(net 246)
	)
	(segment
		(start 125.905 92.1)
		(end 126.56 92.1)
		(width 0.2)
		(layer "F.Cu")
		(net 246)
	)
	(segment
		(start 129.375 93.6)
		(end 129.375 92.53)
		(width 0.2)
		(layer "F.Cu")
		(net 246)
	)
	(segment
		(start 128.945 92.1)
		(end 128.025 92.1)
		(width 0.2)
		(layer "F.Cu")
		(net 246)
	)
	(segment
		(start 132.925 98.7)
		(end 132.925 97.15)
		(width 0.2)
		(layer "F.Cu")
		(net 246)
	)
	(segment
		(start 132.925 97.15)
		(end 129.375 93.6)
		(width 0.2)
		(layer "F.Cu")
		(net 246)
	)
	(segment
		(start 125.105 91.3)
		(end 125.905 92.1)
		(width 0.2)
		(layer "F.Cu")
		(net 246)
	)
	(segment
		(start 133.425 97.15)
		(end 133.425 98.7)
		(width 0.2)
		(layer "F.Cu")
		(net 247)
	)
	(segment
		(start 126.555 90.205)
		(end 128.02 90.205)
		(width 0.2)
		(layer "F.Cu")
		(net 247)
	)
	(segment
		(start 128.025 90.2)
		(end 129.2 90.2)
		(width 0.2)
		(layer "F.Cu")
		(net 247)
	)
	(segment
		(start 129.755 93.48)
		(end 133.425 97.15)
		(width 0.2)
		(layer "F.Cu")
		(net 247)
	)
	(segment
		(start 128.02 90.205)
		(end 128.025 90.2)
		(width 0.2)
		(layer "F.Cu")
		(net 247)
	)
	(segment
		(start 129.755 90.755)
		(end 129.755 93.48)
		(width 0.2)
		(layer "F.Cu")
		(net 247)
	)
	(segment
		(start 129.2 90.2)
		(end 129.755 90.755)
		(width 0.2)
		(layer "F.Cu")
		(net 247)
	)
	(segment
		(start 125.57 89.56)
		(end 125.57 85.47)
		(width 0.2)
		(layer "F.Cu")
		(net 247)
	)
	(segment
		(start 126.555 90.205)
		(end 126.215 90.205)
		(width 0.2)
		(layer "F.Cu")
		(net 247)
	)
	(segment
		(start 126.215 90.205)
		(end 125.57 89.56)
		(width 0.2)
		(layer "F.Cu")
		(net 247)
	)
	(segment
		(start 127.115 83.925)
		(end 127.975 83.925)
		(width 0.2)
		(layer "F.Cu")
		(net 247)
	)
	(segment
		(start 125.57 85.47)
		(end 127.115 83.925)
		(width 0.2)
		(layer "F.Cu")
		(net 247)
	)
	(segment
		(start 127.625 73.65)
		(end 127.625 75.465)
		(width 0.2)
		(layer "F.Cu")
		(net 255)
	)
	(segment
		(start 129.441666 75.465)
		(end 129.441666 73.65)
		(width 0.2)
		(layer "F.Cu")
		(net 256)
	)
	(segment
		(start 131.258332 73.65)
		(end 131.258332 75.465)
		(width 0.2)
		(layer "F.Cu")
		(net 257)
	)
	(segment
		(start 133.075 75.465)
		(end 133.075 73.65)
		(width 0.2)
		(layer "F.Cu")
		(net 258)
	)
	(zone
		(net 188)
		(net_name "VDD2")
		(layer "F.Cu")
		(hatch edge 0.508)
		(connect_pads yes
			(clearance 0.1)
		)
		(min_thickness 0.254)
		(filled_areas_thickness no)
		(fill yes
			(thermal_gap 0.508)
			(thermal_bridge_width 0.508)
		)
		(polygon
			(pts
				(xy 128.025 98.95) (xy 124.325 98.95) (xy 124.325 95.6) (xy 128.025 95.6)
			)
		)
	)
	(zone
		(net 0)
		(net_name "")
		(layer "F.Mask")
		(hatch edge 0.508)
		(connect_pads
			(clearance 0.508)
		)
		(min_thickness 0.254)
		(filled_areas_thickness no)
		(fill yes
			(thermal_gap 0.508)
			(thermal_bridge_width 0.508)
		)
		(polygon
			(pts
				(xy 136.85 97.25) (xy 139.5 97.25) (xy 139.5 100.15) (xy 136.85 100.15)
			)
		)
	)
	(zone
		(net 187)
		(net_name "VDD1")
		(layer "B.Cu")
		(hatch edge 0.508)
		(connect_pads yes
			(clearance 0.15)
		)
		(min_thickness 0.254)
		(filled_areas_thickness no)
		(fill yes
			(thermal_gap 0.508)
			(thermal_bridge_width 0.508)
			(smoothing fillet)
			(radius 0.5)
		)
		(polygon
			(pts
				(xy 132.175 95.315) (xy 132.175 98.9) (xy 130.125 98.9) (xy 130.125 95.32) (xy 121.03 95.33) (xy 120.975 80.45)
				(xy 134.975 80.45) (xy 134.975 95.315)
			)
		)
	)
	(zone
		(net 189)
		(net_name "VDDQ")
		(layer "B.Cu")
		(hatch edge 0.508)
		(connect_pads yes
			(clearance 0.1)
		)
		(min_thickness 0.254)
		(filled_areas_thickness no)
		(fill yes
			(thermal_gap 0.508)
			(thermal_bridge_width 0.508)
		)
		(polygon
			(pts
				(xy 165.825 98.8) (xy 164.525 98.8) (xy 164.525 96.95) (xy 163.275 96.95) (xy 163.275 95.45) (xy 165.825 95.45)
			)
		)
	)
	(zone
		(net 189)
		(net_name "VDDQ")
		(layer "B.Cu")
		(hatch edge 0.508)
		(connect_pads yes
			(clearance 0.1)
		)
		(min_thickness 0.254)
		(filled_areas_thickness no)
		(fill yes
			(thermal_gap 0.508)
			(thermal_bridge_width 0.508)
		)
		(polygon
			(pts
				(xy 135.075 96.9) (xy 133.775 96.9) (xy 133.775 99) (xy 132.575 99) (xy 132.575 95.5) (xy 135.075 95.5)
			)
		)
	)
	(zone
		(net 0)
		(net_name "")
		(layer "B.Mask")
		(hatch edge 0.508)
		(connect_pads
			(clearance 0.508)
		)
		(min_thickness 0.254)
		(filled_areas_thickness no)
		(fill yes
			(thermal_gap 0.508)
			(thermal_bridge_width 0.508)
		)
		(polygon
			(pts
				(xy 137.05 97.25) (xy 139.7 97.25) (xy 139.7 100.15) (xy 137.05 100.15)
			)
		)
	)
	(zone
		(net 36)
		(net_name "GND")
		(layer "In1.Cu")
		(hatch edge 0.508)
		(connect_pads yes
			(clearance 0.15)
		)
		(min_thickness 0.254)
		(filled_areas_thickness no)
		(fill yes
			(thermal_gap 0.508)
			(thermal_bridge_width 0.508)
		)
		(polygon
			(pts
				(xy 169.575 97.25) (xy 100.125 97.25) (xy 100.05 70.15) (xy 169.5 70.15)
			)
		)
	)
	(zone
		(net 188)
		(net_name "VDD2")
		(layer "In3.Cu")
		(hatch edge 0.508)
		(connect_pads yes
			(clearance 0.1)
		)
		(min_thickness 0.254)
		(filled_areas_thickness no)
		(fill yes
			(thermal_gap 0.508)
			(thermal_bridge_width 0.508)
		)
		(polygon
			(pts
				(xy 166.325 76.3) (xy 166.325 79.05) (xy 140.175 79.05) (xy 140.175 83.6) (xy 124.375 83.6) (xy 124.375 76.35)
			)
		)
	)
	(zone
		(net 189)
		(net_name "VDDQ")
		(layer "In3.Cu")
		(hatch edge 0.508)
		(connect_pads yes
			(clearance 0.1)
		)
		(min_thickness 0.254)
		(filled_areas_thickness no)
		(fill yes
			(thermal_gap 0.508)
			(thermal_bridge_width 0.508)
		)
		(polygon
			(pts
				(xy 166.325 99.6) (xy 157.925 99.6) (xy 157.925 83.7) (xy 156.075 83.7) (xy 156.075 79.25) (xy 166.325 79.25)
			)
		)
	)
	(zone
		(net 189)
		(net_name "VDDQ")
		(layer "In3.Cu")
		(hatch edge 0.508)
		(connect_pads yes
			(clearance 0.1)
		)
		(min_thickness 0.254)
		(filled_areas_thickness no)
		(fill yes
			(thermal_gap 0.508)
			(thermal_bridge_width 0.508)
		)
		(polygon
			(pts
				(xy 140.675 90.1) (xy 140.675 96.95) (xy 139.375 96.95) (xy 139.375 95.3) (xy 137.375 95.3) (xy 137.375 99.55)
				(xy 132.425 99.55) (xy 132.425 90.1)
			)
		)
	)
	(zone
		(net 188)
		(net_name "VDD2")
		(layer "In3.Cu")
		(hatch edge 0.508)
		(connect_pads yes
			(clearance 0.1)
		)
		(min_thickness 0.254)
		(filled_areas_thickness no)
		(fill yes
			(thermal_gap 0.508)
			(thermal_bridge_width 0.508)
		)
		(polygon
			(pts
				(xy 140.575 89.75) (xy 132.075 89.75) (xy 132.075 99.5) (xy 124.375 99.5) (xy 124.375 83.35) (xy 140.575 83.35)
			)
		)
	)
	(zone
		(net 189)
		(net_name "VDDQ")
		(layer "In3.Cu")
		(hatch edge 0.508)
		(connect_pads yes
			(clearance 0.1)
		)
		(min_thickness 0.254)
		(filled_areas_thickness no)
		(fill yes
			(thermal_gap 0.508)
			(thermal_bridge_width 0.508)
		)
		(polygon
			(pts
				(xy 157.525 83.7) (xy 150.925 83.7) (xy 150.925 82.35) (xy 147.675 82.35) (xy 147.675 83.15) (xy 140.375 83.15)
				(xy 140.375 79.25) (xy 157.525 79.25)
			)
		)
	)
	(zone
		(net 188)
		(net_name "VDD2")
		(layer "In3.Cu")
		(hatch edge 0.508)
		(connect_pads yes
			(clearance 0.1)
		)
		(min_thickness 0.254)
		(filled_areas_thickness no)
		(fill yes
			(thermal_gap 0.508)
			(thermal_bridge_width 0.508)
		)
		(polygon
			(pts
				(xy 150.675 83.95) (xy 157.575 83.95) (xy 157.575 90.4) (xy 154.725 90.4) (xy 154.725 89.15) (xy 151.375 89.15)
				(xy 151.375 89.6) (xy 147.375 89.6) (xy 147.375 88.85) (xy 144.175 88.85) (xy 144.175 89.75) (xy 140.325 89.75)
				(xy 140.325 83.35) (xy 147.925 83.35) (xy 147.925 82.5) (xy 150.675 82.5)
			)
		)
	)
	(zone
		(net 189)
		(net_name "VDDQ")
		(layer "In3.Cu")
		(hatch edge 0.508)
		(connect_pads yes
			(clearance 0.15)
		)
		(min_thickness 0.254)
		(filled_areas_thickness no)
		(fill yes
			(thermal_gap 0.508)
			(thermal_bridge_width 0.508)
		)
		(polygon
			(pts
				(xy 147.075 89.85) (xy 151.575 89.85) (xy 151.575 89.3) (xy 154.525 89.3) (xy 154.525 90.65) (xy 158.075 90.65)
				(xy 158.075 99.65) (xy 140.325 99.65) (xy 140.325 90.1) (xy 144.475 90.1) (xy 144.475 89.1) (xy 147.075 89.1)
			)
		)
	)
	(zone
		(net 36)
		(net_name "GND")
		(layer "In4.Cu")
		(hatch edge 0.508)
		(connect_pads yes
			(clearance 0.15)
		)
		(min_thickness 0.254)
		(filled_areas_thickness no)
		(fill yes
			(thermal_gap 0.508)
			(thermal_bridge_width 0.508)
		)
		(polygon
			(pts
				(xy 169.625 97.1) (xy 100.075 97.1) (xy 100.025 70.1) (xy 100.025 70.05) (xy 169.625 70.05)
			)
		)
	)
)
